FILE_TYPE = MACRO_DRAWING;
SET COLOR_WIRE YELLOW;
SET COLOR_PROP ORANGE;
SET COLOR_DOT WHITE;
SET COLOR_ARC YELLOW;
SET COLOR_BODY GREEN;
SET COLOR_NOTE PURPLE;
SET PROP_DISPLAY VALUE;
SET PAGE_NUMBER P60;
FORCEADD TAP..1
R 2
(-25 3950);
FORCEPROP 3 LASTPIN (25 3950) SIG_NAME P5E_CPU1_PE0_RX_DP<13>
J 0
(35 3960);
DISPLAY 0.659574 (35 3960);
PAINT MONO (35 3960);
DISPLAY INVISIBLE (35 3960);
FORCEPROP 1 LASTPIN (25 3950) BN 13
J 2
(37 3958);
DISPLAY 0.680851 (37 3958);
PAINT GREEN (37 3958);
FORCEPROP 2 LAST CDS_LIB standard
J 0
(-25 3950);
DISPLAY INVISIBLE (-25 3950);
FORCEPROP 1 LAST BODY_TYPE PLUMBING
J 2
(-25 4000);
DISPLAY 0.872340 (-25 4000);
PAINT GREEN (-25 4000);
DISPLAY INVISIBLE (-25 4000);
FORCEPROP 1 LAST HDL_TAP TRUE
J 2
(-350 3825);
DISPLAY 0.872340 (-350 3825);
DISPLAY INVISIBLE (-350 3825);
FORCEPROP 1 LAST PATH I304
J 2
(-23 3950);
DISPLAY 0.872340 (-23 3950);
PAINT GREEN (-23 3950);
DISPLAY INVISIBLE (-23 3950);
FORCEADD TAP..1
R 2
(-25 3900);
FORCEPROP 3 LASTPIN (25 3900) SIG_NAME P5E_CPU1_PE0_RX_DP<12>
J 0
(35 3910);
DISPLAY 0.659574 (35 3910);
PAINT MONO (35 3910);
DISPLAY INVISIBLE (35 3910);
FORCEPROP 1 LASTPIN (25 3900) BN 12
J 2
(37 3908);
DISPLAY 0.680851 (37 3908);
PAINT GREEN (37 3908);
FORCEPROP 2 LAST CDS_LIB standard
J 0
(-25 3900);
DISPLAY INVISIBLE (-25 3900);
FORCEPROP 1 LAST BODY_TYPE PLUMBING
J 2
(-25 3950);
DISPLAY 0.872340 (-25 3950);
PAINT GREEN (-25 3950);
DISPLAY INVISIBLE (-25 3950);
FORCEPROP 1 LAST HDL_TAP TRUE
J 2
(-350 3775);
DISPLAY 0.872340 (-350 3775);
DISPLAY INVISIBLE (-350 3775);
FORCEPROP 1 LAST PATH I305
J 2
(-23 3900);
DISPLAY 0.872340 (-23 3900);
PAINT GREEN (-23 3900);
DISPLAY INVISIBLE (-23 3900);
FORCEADD TAP..1
R 2
(-25 4050);
FORCEPROP 3 LASTPIN (25 4050) SIG_NAME P5E_CPU1_PE0_RX_DP<15>
J 0
(35 4060);
DISPLAY 0.659574 (35 4060);
PAINT MONO (35 4060);
DISPLAY INVISIBLE (35 4060);
FORCEPROP 1 LASTPIN (25 4050) BN 15
J 2
(37 4058);
DISPLAY 0.680851 (37 4058);
PAINT GREEN (37 4058);
FORCEPROP 2 LAST CDS_LIB standard
J 0
(-25 4050);
DISPLAY INVISIBLE (-25 4050);
FORCEPROP 1 LAST BODY_TYPE PLUMBING
J 2
(-25 4100);
DISPLAY 0.872340 (-25 4100);
PAINT GREEN (-25 4100);
DISPLAY INVISIBLE (-25 4100);
FORCEPROP 1 LAST HDL_TAP TRUE
J 2
(-350 3925);
DISPLAY 0.872340 (-350 3925);
DISPLAY INVISIBLE (-350 3925);
FORCEPROP 1 LAST PATH I306
J 2
(-23 4050);
DISPLAY 0.872340 (-23 4050);
PAINT GREEN (-23 4050);
DISPLAY INVISIBLE (-23 4050);
FORCEADD TAP..1
R 2
(-25 4000);
FORCEPROP 3 LASTPIN (25 4000) SIG_NAME P5E_CPU1_PE0_RX_DP<14>
J 0
(35 4010);
DISPLAY 0.659574 (35 4010);
PAINT MONO (35 4010);
DISPLAY INVISIBLE (35 4010);
FORCEPROP 1 LASTPIN (25 4000) BN 14
J 2
(37 4008);
DISPLAY 0.680851 (37 4008);
PAINT GREEN (37 4008);
FORCEPROP 2 LAST CDS_LIB standard
J 0
(-25 4000);
DISPLAY INVISIBLE (-25 4000);
FORCEPROP 1 LAST BODY_TYPE PLUMBING
J 2
(-25 4050);
DISPLAY 0.872340 (-25 4050);
PAINT GREEN (-25 4050);
DISPLAY INVISIBLE (-25 4050);
FORCEPROP 1 LAST HDL_TAP TRUE
J 2
(-350 3875);
DISPLAY 0.872340 (-350 3875);
DISPLAY INVISIBLE (-350 3875);
FORCEPROP 1 LAST PATH I307
J 2
(-23 4000);
DISPLAY 0.872340 (-23 4000);
PAINT GREEN (-23 4000);
DISPLAY INVISIBLE (-23 4000);
FORCEADD TAP..1
R 2
(-25 3850);
FORCEPROP 3 LASTPIN (25 3850) SIG_NAME P5E_CPU1_PE0_RX_DP<11>
J 0
(35 3860);
DISPLAY 0.659574 (35 3860);
PAINT MONO (35 3860);
DISPLAY INVISIBLE (35 3860);
FORCEPROP 1 LASTPIN (25 3850) BN 11
J 2
(37 3858);
DISPLAY 0.680851 (37 3858);
PAINT GREEN (37 3858);
FORCEPROP 2 LAST CDS_LIB standard
J 0
(-25 3850);
DISPLAY INVISIBLE (-25 3850);
FORCEPROP 1 LAST BODY_TYPE PLUMBING
J 2
(-25 3900);
DISPLAY 0.872340 (-25 3900);
PAINT GREEN (-25 3900);
DISPLAY INVISIBLE (-25 3900);
FORCEPROP 1 LAST HDL_TAP TRUE
J 2
(-350 3725);
DISPLAY 0.872340 (-350 3725);
DISPLAY INVISIBLE (-350 3725);
FORCEPROP 1 LAST PATH I308
J 2
(-23 3850);
DISPLAY 0.872340 (-23 3850);
PAINT GREEN (-23 3850);
DISPLAY INVISIBLE (-23 3850);
FORCEADD TAP..1
R 2
(-25 3800);
FORCEPROP 3 LASTPIN (25 3800) SIG_NAME P5E_CPU1_PE0_RX_DP<10>
J 0
(35 3810);
DISPLAY 0.659574 (35 3810);
PAINT MONO (35 3810);
DISPLAY INVISIBLE (35 3810);
FORCEPROP 1 LASTPIN (25 3800) BN 10
J 2
(37 3808);
DISPLAY 0.680851 (37 3808);
PAINT GREEN (37 3808);
FORCEPROP 2 LAST CDS_LIB standard
J 0
(-25 3800);
DISPLAY INVISIBLE (-25 3800);
FORCEPROP 1 LAST BODY_TYPE PLUMBING
J 2
(-25 3850);
DISPLAY 0.872340 (-25 3850);
PAINT GREEN (-25 3850);
DISPLAY INVISIBLE (-25 3850);
FORCEPROP 1 LAST HDL_TAP TRUE
J 2
(-350 3675);
DISPLAY 0.872340 (-350 3675);
DISPLAY INVISIBLE (-350 3675);
FORCEPROP 1 LAST PATH I309
J 2
(-23 3800);
DISPLAY 0.872340 (-23 3800);
PAINT GREEN (-23 3800);
DISPLAY INVISIBLE (-23 3800);
FORCEADD TAP..1
R 2
(-25 3700);
FORCEPROP 3 LASTPIN (25 3700) SIG_NAME P5E_CPU1_PE0_RX_DP<8>
J 0
(35 3710);
DISPLAY 0.659574 (35 3710);
PAINT MONO (35 3710);
DISPLAY INVISIBLE (35 3710);
FORCEPROP 1 LASTPIN (25 3700) BN 8
J 2
(37 3708);
DISPLAY 0.680851 (37 3708);
PAINT GREEN (37 3708);
FORCEPROP 2 LAST CDS_LIB standard
J 0
(-25 3700);
DISPLAY INVISIBLE (-25 3700);
FORCEPROP 1 LAST BODY_TYPE PLUMBING
J 2
(-25 3750);
DISPLAY 0.872340 (-25 3750);
PAINT GREEN (-25 3750);
DISPLAY INVISIBLE (-25 3750);
FORCEPROP 1 LAST HDL_TAP TRUE
J 2
(-350 3575);
DISPLAY 0.872340 (-350 3575);
DISPLAY INVISIBLE (-350 3575);
FORCEPROP 1 LAST PATH I310
J 2
(-23 3700);
DISPLAY 0.872340 (-23 3700);
PAINT GREEN (-23 3700);
DISPLAY INVISIBLE (-23 3700);
FORCEADD TAP..1
R 2
(-25 3750);
FORCEPROP 3 LASTPIN (25 3750) SIG_NAME P5E_CPU1_PE0_RX_DP<9>
J 0
(35 3760);
DISPLAY 0.659574 (35 3760);
PAINT MONO (35 3760);
DISPLAY INVISIBLE (35 3760);
FORCEPROP 1 LASTPIN (25 3750) BN 9
J 2
(37 3758);
DISPLAY 0.680851 (37 3758);
PAINT GREEN (37 3758);
FORCEPROP 2 LAST CDS_LIB standard
J 0
(-25 3750);
DISPLAY INVISIBLE (-25 3750);
FORCEPROP 1 LAST BODY_TYPE PLUMBING
J 2
(-25 3800);
DISPLAY 0.872340 (-25 3800);
PAINT GREEN (-25 3800);
DISPLAY INVISIBLE (-25 3800);
FORCEPROP 1 LAST HDL_TAP TRUE
J 2
(-350 3625);
DISPLAY 0.872340 (-350 3625);
DISPLAY INVISIBLE (-350 3625);
FORCEPROP 1 LAST PATH I311
J 2
(-23 3750);
DISPLAY 0.872340 (-23 3750);
PAINT GREEN (-23 3750);
DISPLAY INVISIBLE (-23 3750);
FORCEADD TAP..1
R 2
(-25 3650);
FORCEPROP 3 LASTPIN (25 3650) SIG_NAME P5E_CPU1_PE0_RX_DP<7>
J 0
(35 3660);
DISPLAY 0.659574 (35 3660);
PAINT MONO (35 3660);
DISPLAY INVISIBLE (35 3660);
FORCEPROP 1 LASTPIN (25 3650) BN 7
J 2
(37 3658);
DISPLAY 0.680851 (37 3658);
PAINT GREEN (37 3658);
FORCEPROP 2 LAST CDS_LIB standard
J 0
(-25 3650);
DISPLAY INVISIBLE (-25 3650);
FORCEPROP 1 LAST BODY_TYPE PLUMBING
J 2
(-25 3700);
DISPLAY 0.872340 (-25 3700);
PAINT GREEN (-25 3700);
DISPLAY INVISIBLE (-25 3700);
FORCEPROP 1 LAST HDL_TAP TRUE
J 2
(-350 3525);
DISPLAY 0.872340 (-350 3525);
DISPLAY INVISIBLE (-350 3525);
FORCEPROP 1 LAST PATH I312
J 2
(-23 3650);
DISPLAY 0.872340 (-23 3650);
PAINT GREEN (-23 3650);
DISPLAY INVISIBLE (-23 3650);
FORCEADD TAP..1
R 2
(-25 3600);
FORCEPROP 3 LASTPIN (25 3600) SIG_NAME P5E_CPU1_PE0_RX_DP<6>
J 0
(35 3610);
DISPLAY 0.659574 (35 3610);
PAINT MONO (35 3610);
DISPLAY INVISIBLE (35 3610);
FORCEPROP 1 LASTPIN (25 3600) BN 6
J 2
(37 3608);
DISPLAY 0.680851 (37 3608);
PAINT GREEN (37 3608);
FORCEPROP 2 LAST CDS_LIB standard
J 0
(-25 3600);
DISPLAY INVISIBLE (-25 3600);
FORCEPROP 1 LAST BODY_TYPE PLUMBING
J 2
(-25 3650);
DISPLAY 0.872340 (-25 3650);
PAINT GREEN (-25 3650);
DISPLAY INVISIBLE (-25 3650);
FORCEPROP 1 LAST HDL_TAP TRUE
J 2
(-350 3475);
DISPLAY 0.872340 (-350 3475);
DISPLAY INVISIBLE (-350 3475);
FORCEPROP 1 LAST PATH I313
J 2
(-23 3600);
DISPLAY 0.872340 (-23 3600);
PAINT GREEN (-23 3600);
DISPLAY INVISIBLE (-23 3600);
FORCEADD TAP..1
R 2
(-25 3550);
FORCEPROP 3 LASTPIN (25 3550) SIG_NAME P5E_CPU1_PE0_RX_DP<5>
J 0
(35 3560);
DISPLAY 0.659574 (35 3560);
PAINT MONO (35 3560);
DISPLAY INVISIBLE (35 3560);
FORCEPROP 1 LASTPIN (25 3550) BN 5
J 2
(37 3558);
DISPLAY 0.680851 (37 3558);
PAINT GREEN (37 3558);
FORCEPROP 2 LAST CDS_LIB standard
J 0
(-25 3550);
DISPLAY INVISIBLE (-25 3550);
FORCEPROP 1 LAST BODY_TYPE PLUMBING
J 2
(-25 3600);
DISPLAY 0.872340 (-25 3600);
PAINT GREEN (-25 3600);
DISPLAY INVISIBLE (-25 3600);
FORCEPROP 1 LAST HDL_TAP TRUE
J 2
(-350 3425);
DISPLAY 0.872340 (-350 3425);
DISPLAY INVISIBLE (-350 3425);
FORCEPROP 1 LAST PATH I314
J 2
(-23 3550);
DISPLAY 0.872340 (-23 3550);
PAINT GREEN (-23 3550);
DISPLAY INVISIBLE (-23 3550);
FORCEADD TAP..1
R 2
(-25 3450);
FORCEPROP 3 LASTPIN (25 3450) SIG_NAME P5E_CPU1_PE0_RX_DP<3>
J 0
(35 3460);
DISPLAY 0.659574 (35 3460);
PAINT MONO (35 3460);
DISPLAY INVISIBLE (35 3460);
FORCEPROP 1 LASTPIN (25 3450) BN 3
J 2
(37 3458);
DISPLAY 0.680851 (37 3458);
PAINT GREEN (37 3458);
FORCEPROP 2 LAST CDS_LIB standard
J 0
(-25 3450);
DISPLAY INVISIBLE (-25 3450);
FORCEPROP 1 LAST BODY_TYPE PLUMBING
J 2
(-25 3500);
DISPLAY 0.872340 (-25 3500);
PAINT GREEN (-25 3500);
DISPLAY INVISIBLE (-25 3500);
FORCEPROP 1 LAST HDL_TAP TRUE
J 2
(-350 3325);
DISPLAY 0.872340 (-350 3325);
DISPLAY INVISIBLE (-350 3325);
FORCEPROP 1 LAST PATH I315
J 2
(-23 3450);
DISPLAY 0.872340 (-23 3450);
PAINT GREEN (-23 3450);
DISPLAY INVISIBLE (-23 3450);
FORCEADD TAP..1
R 2
(-25 3500);
FORCEPROP 3 LASTPIN (25 3500) SIG_NAME P5E_CPU1_PE0_RX_DP<4>
J 0
(35 3510);
DISPLAY 0.659574 (35 3510);
PAINT MONO (35 3510);
DISPLAY INVISIBLE (35 3510);
FORCEPROP 1 LASTPIN (25 3500) BN 4
J 2
(37 3508);
DISPLAY 0.680851 (37 3508);
PAINT GREEN (37 3508);
FORCEPROP 2 LAST CDS_LIB standard
J 0
(-25 3500);
DISPLAY INVISIBLE (-25 3500);
FORCEPROP 1 LAST BODY_TYPE PLUMBING
J 2
(-25 3550);
DISPLAY 0.872340 (-25 3550);
PAINT GREEN (-25 3550);
DISPLAY INVISIBLE (-25 3550);
FORCEPROP 1 LAST HDL_TAP TRUE
J 2
(-350 3375);
DISPLAY 0.872340 (-350 3375);
DISPLAY INVISIBLE (-350 3375);
FORCEPROP 1 LAST PATH I316
J 2
(-23 3500);
DISPLAY 0.872340 (-23 3500);
PAINT GREEN (-23 3500);
DISPLAY INVISIBLE (-23 3500);
FORCEADD TAP..1
R 2
(-25 3300);
FORCEPROP 3 LASTPIN (25 3300) SIG_NAME P5E_CPU1_PE0_RX_DP<0>
J 0
(35 3310);
DISPLAY 0.659574 (35 3310);
PAINT MONO (35 3310);
DISPLAY INVISIBLE (35 3310);
FORCEPROP 1 LASTPIN (25 3300) BN 0
J 2
(37 3308);
DISPLAY 0.680851 (37 3308);
PAINT GREEN (37 3308);
FORCEPROP 2 LAST CDS_LIB standard
J 0
(-25 3300);
DISPLAY INVISIBLE (-25 3300);
FORCEPROP 1 LAST BODY_TYPE PLUMBING
J 2
(-25 3350);
DISPLAY 0.872340 (-25 3350);
PAINT GREEN (-25 3350);
DISPLAY INVISIBLE (-25 3350);
FORCEPROP 1 LAST HDL_TAP TRUE
J 2
(-350 3175);
DISPLAY 0.872340 (-350 3175);
DISPLAY INVISIBLE (-350 3175);
FORCEPROP 1 LAST PATH I317
J 2
(-23 3300);
DISPLAY 0.872340 (-23 3300);
PAINT GREEN (-23 3300);
DISPLAY INVISIBLE (-23 3300);
FORCEADD TAP..1
R 2
(-25 3400);
FORCEPROP 3 LASTPIN (25 3400) SIG_NAME P5E_CPU1_PE0_RX_DP<2>
J 0
(35 3410);
DISPLAY 0.659574 (35 3410);
PAINT MONO (35 3410);
DISPLAY INVISIBLE (35 3410);
FORCEPROP 1 LASTPIN (25 3400) BN 2
J 2
(37 3408);
DISPLAY 0.680851 (37 3408);
PAINT GREEN (37 3408);
FORCEPROP 2 LAST CDS_LIB standard
J 0
(-25 3400);
DISPLAY INVISIBLE (-25 3400);
FORCEPROP 1 LAST BODY_TYPE PLUMBING
J 2
(-25 3450);
DISPLAY 0.872340 (-25 3450);
PAINT GREEN (-25 3450);
DISPLAY INVISIBLE (-25 3450);
FORCEPROP 1 LAST HDL_TAP TRUE
J 2
(-350 3275);
DISPLAY 0.872340 (-350 3275);
DISPLAY INVISIBLE (-350 3275);
FORCEPROP 1 LAST PATH I318
J 2
(-23 3400);
DISPLAY 0.872340 (-23 3400);
PAINT GREEN (-23 3400);
DISPLAY INVISIBLE (-23 3400);
FORCEADD TAP..1
R 2
(-25 3350);
FORCEPROP 3 LASTPIN (25 3350) SIG_NAME P5E_CPU1_PE0_RX_DP<1>
J 0
(35 3360);
DISPLAY 0.659574 (35 3360);
PAINT MONO (35 3360);
DISPLAY INVISIBLE (35 3360);
FORCEPROP 1 LASTPIN (25 3350) BN 1
J 2
(37 3358);
DISPLAY 0.680851 (37 3358);
PAINT GREEN (37 3358);
FORCEPROP 2 LAST CDS_LIB standard
J 0
(-25 3350);
DISPLAY INVISIBLE (-25 3350);
FORCEPROP 1 LAST BODY_TYPE PLUMBING
J 2
(-25 3400);
DISPLAY 0.872340 (-25 3400);
PAINT GREEN (-25 3400);
DISPLAY INVISIBLE (-25 3400);
FORCEPROP 1 LAST HDL_TAP TRUE
J 2
(-350 3225);
DISPLAY 0.872340 (-350 3225);
DISPLAY INVISIBLE (-350 3225);
FORCEPROP 1 LAST PATH I319
J 2
(-23 3350);
DISPLAY 0.872340 (-23 3350);
PAINT GREEN (-23 3350);
DISPLAY INVISIBLE (-23 3350);
FORCEADD OFFPAGE..1
(-1275 4075);
FORCEPROP 2 LAST $XR1 143 
J 0
(-1647 4075);
DISPLAY 0.638298 (-1647 4075);
PAINT MONO (-1647 4075);
FORCEPROP 2 LAST $XR0 142 
J 0
(-1527 4075);
DISPLAY 0.638298 (-1527 4075);
PAINT MONO (-1527 4075);
FORCEPROP 2 LAST CDS_LIB standard
J 0
(-1275 4075);
PAINT MONO (-1275 4075);
DISPLAY INVISIBLE (-1275 4075);
FORCEPROP 1 LAST OFFPAGE TRUE
J 0
(-950 3950);
DISPLAY 0.872340 (-950 3950);
DISPLAY INVISIBLE (-950 3950);
FORCEPROP 1 LAST COMMENT_BODY TRUE
J 0
(-1150 3975);
DISPLAY 0.872340 (-1150 3975);
PAINT GREEN (-1150 3975);
DISPLAY INVISIBLE (-1150 3975);
FORCEPROP 2 LAST PATH I320
J 0
(-1525 4125);
DISPLAY 1.021277 (-1525 4125);
DISPLAY INVISIBLE (-1525 4125);
FORCEADD TAP..1
R 2
(-25 2500);
FORCEPROP 3 LASTPIN (25 2500) SIG_NAME P5E_CPU1_PE0_RX_DN<1>
J 0
(35 2510);
DISPLAY 0.659574 (35 2510);
PAINT MONO (35 2510);
DISPLAY INVISIBLE (35 2510);
FORCEPROP 1 LASTPIN (25 2500) BN 1
J 2
(37 2508);
DISPLAY 0.680851 (37 2508);
PAINT GREEN (37 2508);
FORCEPROP 2 LAST CDS_LIB standard
J 0
(-25 2500);
DISPLAY INVISIBLE (-25 2500);
FORCEPROP 1 LAST BODY_TYPE PLUMBING
J 2
(-25 2550);
DISPLAY 0.872340 (-25 2550);
PAINT GREEN (-25 2550);
DISPLAY INVISIBLE (-25 2550);
FORCEPROP 1 LAST HDL_TAP TRUE
J 2
(-350 2375);
DISPLAY 0.872340 (-350 2375);
DISPLAY INVISIBLE (-350 2375);
FORCEPROP 1 LAST PATH I321
J 2
(-23 2500);
DISPLAY 0.872340 (-23 2500);
PAINT GREEN (-23 2500);
DISPLAY INVISIBLE (-23 2500);
FORCEADD TAP..1
R 2
(-25 3200);
FORCEPROP 3 LASTPIN (25 3200) SIG_NAME P5E_CPU1_PE0_RX_DN<15>
J 0
(35 3210);
DISPLAY 0.659574 (35 3210);
PAINT MONO (35 3210);
DISPLAY INVISIBLE (35 3210);
FORCEPROP 1 LASTPIN (25 3200) BN 15
J 2
(37 3208);
DISPLAY 0.680851 (37 3208);
PAINT GREEN (37 3208);
FORCEPROP 2 LAST CDS_LIB standard
J 0
(-25 3200);
DISPLAY INVISIBLE (-25 3200);
FORCEPROP 1 LAST BODY_TYPE PLUMBING
J 2
(-25 3250);
DISPLAY 0.872340 (-25 3250);
PAINT GREEN (-25 3250);
DISPLAY INVISIBLE (-25 3250);
FORCEPROP 1 LAST HDL_TAP TRUE
J 2
(-350 3075);
DISPLAY 0.872340 (-350 3075);
DISPLAY INVISIBLE (-350 3075);
FORCEPROP 1 LAST PATH I322
J 2
(-23 3200);
DISPLAY 0.872340 (-23 3200);
PAINT GREEN (-23 3200);
DISPLAY INVISIBLE (-23 3200);
FORCEADD TAP..1
R 2
(-25 3150);
FORCEPROP 3 LASTPIN (25 3150) SIG_NAME P5E_CPU1_PE0_RX_DN<14>
J 0
(35 3160);
DISPLAY 0.659574 (35 3160);
PAINT MONO (35 3160);
DISPLAY INVISIBLE (35 3160);
FORCEPROP 1 LASTPIN (25 3150) BN 14
J 2
(37 3158);
DISPLAY 0.680851 (37 3158);
PAINT GREEN (37 3158);
FORCEPROP 2 LAST CDS_LIB standard
J 0
(-25 3150);
DISPLAY INVISIBLE (-25 3150);
FORCEPROP 1 LAST BODY_TYPE PLUMBING
J 2
(-25 3200);
DISPLAY 0.872340 (-25 3200);
PAINT GREEN (-25 3200);
DISPLAY INVISIBLE (-25 3200);
FORCEPROP 1 LAST HDL_TAP TRUE
J 2
(-350 3025);
DISPLAY 0.872340 (-350 3025);
DISPLAY INVISIBLE (-350 3025);
FORCEPROP 1 LAST PATH I323
J 2
(-23 3150);
DISPLAY 0.872340 (-23 3150);
PAINT GREEN (-23 3150);
DISPLAY INVISIBLE (-23 3150);
FORCEADD TAP..1
R 2
(-25 3100);
FORCEPROP 3 LASTPIN (25 3100) SIG_NAME P5E_CPU1_PE0_RX_DN<13>
J 0
(35 3110);
DISPLAY 0.659574 (35 3110);
PAINT MONO (35 3110);
DISPLAY INVISIBLE (35 3110);
FORCEPROP 1 LASTPIN (25 3100) BN 13
J 2
(37 3108);
DISPLAY 0.680851 (37 3108);
PAINT GREEN (37 3108);
FORCEPROP 2 LAST CDS_LIB standard
J 0
(-25 3100);
DISPLAY INVISIBLE (-25 3100);
FORCEPROP 1 LAST BODY_TYPE PLUMBING
J 2
(-25 3150);
DISPLAY 0.872340 (-25 3150);
PAINT GREEN (-25 3150);
DISPLAY INVISIBLE (-25 3150);
FORCEPROP 1 LAST HDL_TAP TRUE
J 2
(-350 2975);
DISPLAY 0.872340 (-350 2975);
DISPLAY INVISIBLE (-350 2975);
FORCEPROP 1 LAST PATH I324
J 2
(-23 3100);
DISPLAY 0.872340 (-23 3100);
PAINT GREEN (-23 3100);
DISPLAY INVISIBLE (-23 3100);
FORCEADD TAP..1
R 2
(-25 3050);
FORCEPROP 3 LASTPIN (25 3050) SIG_NAME P5E_CPU1_PE0_RX_DN<12>
J 0
(35 3060);
DISPLAY 0.659574 (35 3060);
PAINT MONO (35 3060);
DISPLAY INVISIBLE (35 3060);
FORCEPROP 1 LASTPIN (25 3050) BN 12
J 2
(37 3058);
DISPLAY 0.680851 (37 3058);
PAINT GREEN (37 3058);
FORCEPROP 2 LAST CDS_LIB standard
J 0
(-25 3050);
DISPLAY INVISIBLE (-25 3050);
FORCEPROP 1 LAST BODY_TYPE PLUMBING
J 2
(-25 3100);
DISPLAY 0.872340 (-25 3100);
PAINT GREEN (-25 3100);
DISPLAY INVISIBLE (-25 3100);
FORCEPROP 1 LAST HDL_TAP TRUE
J 2
(-350 2925);
DISPLAY 0.872340 (-350 2925);
DISPLAY INVISIBLE (-350 2925);
FORCEPROP 1 LAST PATH I325
J 2
(-23 3050);
DISPLAY 0.872340 (-23 3050);
PAINT GREEN (-23 3050);
DISPLAY INVISIBLE (-23 3050);
FORCEADD TAP..1
R 2
(-25 3000);
FORCEPROP 3 LASTPIN (25 3000) SIG_NAME P5E_CPU1_PE0_RX_DN<11>
J 0
(35 3010);
DISPLAY 0.659574 (35 3010);
PAINT MONO (35 3010);
DISPLAY INVISIBLE (35 3010);
FORCEPROP 1 LASTPIN (25 3000) BN 11
J 2
(37 3008);
DISPLAY 0.680851 (37 3008);
PAINT GREEN (37 3008);
FORCEPROP 2 LAST CDS_LIB standard
J 0
(-25 3000);
DISPLAY INVISIBLE (-25 3000);
FORCEPROP 1 LAST BODY_TYPE PLUMBING
J 2
(-25 3050);
DISPLAY 0.872340 (-25 3050);
PAINT GREEN (-25 3050);
DISPLAY INVISIBLE (-25 3050);
FORCEPROP 1 LAST HDL_TAP TRUE
J 2
(-350 2875);
DISPLAY 0.872340 (-350 2875);
DISPLAY INVISIBLE (-350 2875);
FORCEPROP 1 LAST PATH I326
J 2
(-23 3000);
DISPLAY 0.872340 (-23 3000);
PAINT GREEN (-23 3000);
DISPLAY INVISIBLE (-23 3000);
FORCEADD TAP..1
R 2
(-25 2950);
FORCEPROP 3 LASTPIN (25 2950) SIG_NAME P5E_CPU1_PE0_RX_DN<10>
J 0
(35 2960);
DISPLAY 0.659574 (35 2960);
PAINT MONO (35 2960);
DISPLAY INVISIBLE (35 2960);
FORCEPROP 1 LASTPIN (25 2950) BN 10
J 2
(37 2958);
DISPLAY 0.680851 (37 2958);
PAINT GREEN (37 2958);
FORCEPROP 2 LAST CDS_LIB standard
J 0
(-25 2950);
DISPLAY INVISIBLE (-25 2950);
FORCEPROP 1 LAST BODY_TYPE PLUMBING
J 2
(-25 3000);
DISPLAY 0.872340 (-25 3000);
PAINT GREEN (-25 3000);
DISPLAY INVISIBLE (-25 3000);
FORCEPROP 1 LAST HDL_TAP TRUE
J 2
(-350 2825);
DISPLAY 0.872340 (-350 2825);
DISPLAY INVISIBLE (-350 2825);
FORCEPROP 1 LAST PATH I327
J 2
(-23 2950);
DISPLAY 0.872340 (-23 2950);
PAINT GREEN (-23 2950);
DISPLAY INVISIBLE (-23 2950);
FORCEADD TAP..1
R 2
(-25 2900);
FORCEPROP 3 LASTPIN (25 2900) SIG_NAME P5E_CPU1_PE0_RX_DN<9>
J 0
(35 2910);
DISPLAY 0.659574 (35 2910);
PAINT MONO (35 2910);
DISPLAY INVISIBLE (35 2910);
FORCEPROP 1 LASTPIN (25 2900) BN 9
J 2
(37 2908);
DISPLAY 0.680851 (37 2908);
PAINT GREEN (37 2908);
FORCEPROP 2 LAST CDS_LIB standard
J 0
(-25 2900);
DISPLAY INVISIBLE (-25 2900);
FORCEPROP 1 LAST BODY_TYPE PLUMBING
J 2
(-25 2950);
DISPLAY 0.872340 (-25 2950);
PAINT GREEN (-25 2950);
DISPLAY INVISIBLE (-25 2950);
FORCEPROP 1 LAST HDL_TAP TRUE
J 2
(-350 2775);
DISPLAY 0.872340 (-350 2775);
DISPLAY INVISIBLE (-350 2775);
FORCEPROP 1 LAST PATH I328
J 2
(-23 2900);
DISPLAY 0.872340 (-23 2900);
PAINT GREEN (-23 2900);
DISPLAY INVISIBLE (-23 2900);
FORCEADD TAP..1
R 2
(-25 2850);
FORCEPROP 3 LASTPIN (25 2850) SIG_NAME P5E_CPU1_PE0_RX_DN<8>
J 0
(35 2860);
DISPLAY 0.659574 (35 2860);
PAINT MONO (35 2860);
DISPLAY INVISIBLE (35 2860);
FORCEPROP 1 LASTPIN (25 2850) BN 8
J 2
(37 2858);
DISPLAY 0.680851 (37 2858);
PAINT GREEN (37 2858);
FORCEPROP 2 LAST CDS_LIB standard
J 0
(-25 2850);
DISPLAY INVISIBLE (-25 2850);
FORCEPROP 1 LAST BODY_TYPE PLUMBING
J 2
(-25 2900);
DISPLAY 0.872340 (-25 2900);
PAINT GREEN (-25 2900);
DISPLAY INVISIBLE (-25 2900);
FORCEPROP 1 LAST HDL_TAP TRUE
J 2
(-350 2725);
DISPLAY 0.872340 (-350 2725);
DISPLAY INVISIBLE (-350 2725);
FORCEPROP 1 LAST PATH I329
J 2
(-23 2850);
DISPLAY 0.872340 (-23 2850);
PAINT GREEN (-23 2850);
DISPLAY INVISIBLE (-23 2850);
FORCEADD TAP..1
R 2
(-25 2750);
FORCEPROP 3 LASTPIN (25 2750) SIG_NAME P5E_CPU1_PE0_RX_DN<6>
J 0
(35 2760);
DISPLAY 0.659574 (35 2760);
PAINT MONO (35 2760);
DISPLAY INVISIBLE (35 2760);
FORCEPROP 1 LASTPIN (25 2750) BN 6
J 2
(37 2758);
DISPLAY 0.680851 (37 2758);
PAINT GREEN (37 2758);
FORCEPROP 2 LAST CDS_LIB standard
J 0
(-25 2750);
DISPLAY INVISIBLE (-25 2750);
FORCEPROP 1 LAST BODY_TYPE PLUMBING
J 2
(-25 2800);
DISPLAY 0.872340 (-25 2800);
PAINT GREEN (-25 2800);
DISPLAY INVISIBLE (-25 2800);
FORCEPROP 1 LAST HDL_TAP TRUE
J 2
(-350 2625);
DISPLAY 0.872340 (-350 2625);
DISPLAY INVISIBLE (-350 2625);
FORCEPROP 1 LAST PATH I330
J 2
(-23 2750);
DISPLAY 0.872340 (-23 2750);
PAINT GREEN (-23 2750);
DISPLAY INVISIBLE (-23 2750);
FORCEADD TAP..1
R 2
(-25 2800);
FORCEPROP 3 LASTPIN (25 2800) SIG_NAME P5E_CPU1_PE0_RX_DN<7>
J 0
(35 2810);
DISPLAY 0.659574 (35 2810);
PAINT MONO (35 2810);
DISPLAY INVISIBLE (35 2810);
FORCEPROP 1 LASTPIN (25 2800) BN 7
J 2
(37 2808);
DISPLAY 0.680851 (37 2808);
PAINT GREEN (37 2808);
FORCEPROP 2 LAST CDS_LIB standard
J 0
(-25 2800);
DISPLAY INVISIBLE (-25 2800);
FORCEPROP 1 LAST BODY_TYPE PLUMBING
J 2
(-25 2850);
DISPLAY 0.872340 (-25 2850);
PAINT GREEN (-25 2850);
DISPLAY INVISIBLE (-25 2850);
FORCEPROP 1 LAST HDL_TAP TRUE
J 2
(-350 2675);
DISPLAY 0.872340 (-350 2675);
DISPLAY INVISIBLE (-350 2675);
FORCEPROP 1 LAST PATH I331
J 2
(-23 2800);
DISPLAY 0.872340 (-23 2800);
PAINT GREEN (-23 2800);
DISPLAY INVISIBLE (-23 2800);
FORCEADD TAP..1
R 2
(-25 2650);
FORCEPROP 3 LASTPIN (25 2650) SIG_NAME P5E_CPU1_PE0_RX_DN<4>
J 0
(35 2660);
DISPLAY 0.659574 (35 2660);
PAINT MONO (35 2660);
DISPLAY INVISIBLE (35 2660);
FORCEPROP 1 LASTPIN (25 2650) BN 4
J 2
(37 2658);
DISPLAY 0.680851 (37 2658);
PAINT GREEN (37 2658);
FORCEPROP 2 LAST CDS_LIB standard
J 0
(-25 2650);
DISPLAY INVISIBLE (-25 2650);
FORCEPROP 1 LAST BODY_TYPE PLUMBING
J 2
(-25 2700);
DISPLAY 0.872340 (-25 2700);
PAINT GREEN (-25 2700);
DISPLAY INVISIBLE (-25 2700);
FORCEPROP 1 LAST HDL_TAP TRUE
J 2
(-350 2525);
DISPLAY 0.872340 (-350 2525);
DISPLAY INVISIBLE (-350 2525);
FORCEPROP 1 LAST PATH I332
J 2
(-23 2650);
DISPLAY 0.872340 (-23 2650);
PAINT GREEN (-23 2650);
DISPLAY INVISIBLE (-23 2650);
FORCEADD TAP..1
R 2
(-25 2700);
FORCEPROP 3 LASTPIN (25 2700) SIG_NAME P5E_CPU1_PE0_RX_DN<5>
J 0
(35 2710);
DISPLAY 0.659574 (35 2710);
PAINT MONO (35 2710);
DISPLAY INVISIBLE (35 2710);
FORCEPROP 1 LASTPIN (25 2700) BN 5
J 2
(37 2708);
DISPLAY 0.680851 (37 2708);
PAINT GREEN (37 2708);
FORCEPROP 2 LAST CDS_LIB standard
J 0
(-25 2700);
DISPLAY INVISIBLE (-25 2700);
FORCEPROP 1 LAST BODY_TYPE PLUMBING
J 2
(-25 2750);
DISPLAY 0.872340 (-25 2750);
PAINT GREEN (-25 2750);
DISPLAY INVISIBLE (-25 2750);
FORCEPROP 1 LAST HDL_TAP TRUE
J 2
(-350 2575);
DISPLAY 0.872340 (-350 2575);
DISPLAY INVISIBLE (-350 2575);
FORCEPROP 1 LAST PATH I333
J 2
(-23 2700);
DISPLAY 0.872340 (-23 2700);
PAINT GREEN (-23 2700);
DISPLAY INVISIBLE (-23 2700);
FORCEADD TAP..1
R 2
(-25 2600);
FORCEPROP 3 LASTPIN (25 2600) SIG_NAME P5E_CPU1_PE0_RX_DN<3>
J 0
(35 2610);
DISPLAY 0.659574 (35 2610);
PAINT MONO (35 2610);
DISPLAY INVISIBLE (35 2610);
FORCEPROP 1 LASTPIN (25 2600) BN 3
J 2
(37 2608);
DISPLAY 0.680851 (37 2608);
PAINT GREEN (37 2608);
FORCEPROP 2 LAST CDS_LIB standard
J 0
(-25 2600);
DISPLAY INVISIBLE (-25 2600);
FORCEPROP 1 LAST BODY_TYPE PLUMBING
J 2
(-25 2650);
DISPLAY 0.872340 (-25 2650);
PAINT GREEN (-25 2650);
DISPLAY INVISIBLE (-25 2650);
FORCEPROP 1 LAST HDL_TAP TRUE
J 2
(-350 2475);
DISPLAY 0.872340 (-350 2475);
DISPLAY INVISIBLE (-350 2475);
FORCEPROP 1 LAST PATH I334
J 2
(-23 2600);
DISPLAY 0.872340 (-23 2600);
PAINT GREEN (-23 2600);
DISPLAY INVISIBLE (-23 2600);
FORCEADD TAP..1
R 2
(-25 2550);
FORCEPROP 3 LASTPIN (25 2550) SIG_NAME P5E_CPU1_PE0_RX_DN<2>
J 0
(35 2560);
DISPLAY 0.659574 (35 2560);
PAINT MONO (35 2560);
DISPLAY INVISIBLE (35 2560);
FORCEPROP 1 LASTPIN (25 2550) BN 2
J 2
(37 2558);
DISPLAY 0.680851 (37 2558);
PAINT GREEN (37 2558);
FORCEPROP 2 LAST CDS_LIB standard
J 0
(-25 2550);
DISPLAY INVISIBLE (-25 2550);
FORCEPROP 1 LAST BODY_TYPE PLUMBING
J 2
(-25 2600);
DISPLAY 0.872340 (-25 2600);
PAINT GREEN (-25 2600);
DISPLAY INVISIBLE (-25 2600);
FORCEPROP 1 LAST HDL_TAP TRUE
J 2
(-350 2425);
DISPLAY 0.872340 (-350 2425);
DISPLAY INVISIBLE (-350 2425);
FORCEPROP 1 LAST PATH I335
J 2
(-23 2550);
DISPLAY 0.872340 (-23 2550);
PAINT GREEN (-23 2550);
DISPLAY INVISIBLE (-23 2550);
FORCEADD TAP..1
R 2
(-25 2450);
FORCEPROP 3 LASTPIN (25 2450) SIG_NAME P5E_CPU1_PE0_RX_DN<0>
J 0
(35 2460);
DISPLAY 0.659574 (35 2460);
PAINT MONO (35 2460);
DISPLAY INVISIBLE (35 2460);
FORCEPROP 1 LASTPIN (25 2450) BN 0
J 2
(37 2458);
DISPLAY 0.680851 (37 2458);
PAINT GREEN (37 2458);
FORCEPROP 2 LAST CDS_LIB standard
J 0
(-25 2450);
DISPLAY INVISIBLE (-25 2450);
FORCEPROP 1 LAST BODY_TYPE PLUMBING
J 2
(-25 2500);
DISPLAY 0.872340 (-25 2500);
PAINT GREEN (-25 2500);
DISPLAY INVISIBLE (-25 2500);
FORCEPROP 1 LAST HDL_TAP TRUE
J 2
(-350 2325);
DISPLAY 0.872340 (-350 2325);
DISPLAY INVISIBLE (-350 2325);
FORCEPROP 1 LAST PATH I336
J 2
(-23 2450);
DISPLAY 0.872340 (-23 2450);
PAINT GREEN (-23 2450);
DISPLAY INVISIBLE (-23 2450);
FORCEADD OFFPAGE..1
(-1275 3225);
FORCEPROP 2 LAST $XR1 143 
J 0
(-1647 3225);
DISPLAY 0.638298 (-1647 3225);
PAINT MONO (-1647 3225);
FORCEPROP 2 LAST $XR0 142 
J 0
(-1527 3225);
DISPLAY 0.638298 (-1527 3225);
PAINT MONO (-1527 3225);
FORCEPROP 2 LAST CDS_LIB standard
J 0
(-1275 3225);
PAINT MONO (-1275 3225);
DISPLAY INVISIBLE (-1275 3225);
FORCEPROP 1 LAST OFFPAGE TRUE
J 0
(-950 3100);
DISPLAY 0.872340 (-950 3100);
DISPLAY INVISIBLE (-950 3100);
FORCEPROP 1 LAST COMMENT_BODY TRUE
J 0
(-1150 3125);
DISPLAY 0.872340 (-1150 3125);
PAINT GREEN (-1150 3125);
DISPLAY INVISIBLE (-1150 3125);
FORCEPROP 2 LAST PATH I337
J 0
(-1525 3275);
DISPLAY 1.021277 (-1525 3275);
DISPLAY INVISIBLE (-1525 3275);
FORCEADD TAP..1
R 2
(-25 225);
FORCEPROP 3 LASTPIN (25 225) SIG_NAME P5E_CPU1_PE1_RX_DN<11>
J 0
(35 235);
DISPLAY 0.659574 (35 235);
PAINT MONO (35 235);
DISPLAY INVISIBLE (35 235);
FORCEPROP 1 LASTPIN (25 225) BN 11
J 2
(37 233);
DISPLAY 0.680851 (37 233);
PAINT GREEN (37 233);
FORCEPROP 2 LAST CDS_LIB standard
J 0
(-25 225);
DISPLAY INVISIBLE (-25 225);
FORCEPROP 1 LAST BODY_TYPE PLUMBING
J 2
(-25 275);
DISPLAY 0.872340 (-25 275);
PAINT GREEN (-25 275);
DISPLAY INVISIBLE (-25 275);
FORCEPROP 1 LAST HDL_TAP TRUE
J 2
(-350 100);
DISPLAY 0.872340 (-350 100);
DISPLAY INVISIBLE (-350 100);
FORCEPROP 1 LAST PATH I338
J 2
(-23 225);
DISPLAY 0.872340 (-23 225);
PAINT GREEN (-23 225);
DISPLAY INVISIBLE (-23 225);
FORCEADD TAP..1
R 2
(-25 175);
FORCEPROP 3 LASTPIN (25 175) SIG_NAME P5E_CPU1_PE1_RX_DN<10>
J 0
(35 185);
DISPLAY 0.659574 (35 185);
PAINT MONO (35 185);
DISPLAY INVISIBLE (35 185);
FORCEPROP 1 LASTPIN (25 175) BN 10
J 2
(37 183);
DISPLAY 0.680851 (37 183);
PAINT GREEN (37 183);
FORCEPROP 2 LAST CDS_LIB standard
J 0
(-25 175);
DISPLAY INVISIBLE (-25 175);
FORCEPROP 1 LAST BODY_TYPE PLUMBING
J 2
(-25 225);
DISPLAY 0.872340 (-25 225);
PAINT GREEN (-25 225);
DISPLAY INVISIBLE (-25 225);
FORCEPROP 1 LAST HDL_TAP TRUE
J 2
(-350 50);
DISPLAY 0.872340 (-350 50);
DISPLAY INVISIBLE (-350 50);
FORCEPROP 1 LAST PATH I339
J 2
(-23 175);
DISPLAY 0.872340 (-23 175);
PAINT GREEN (-23 175);
DISPLAY INVISIBLE (-23 175);
FORCEADD TAP..1
R 2
(-25 125);
FORCEPROP 3 LASTPIN (25 125) SIG_NAME P5E_CPU1_PE1_RX_DN<9>
J 0
(35 135);
DISPLAY 0.659574 (35 135);
PAINT MONO (35 135);
DISPLAY INVISIBLE (35 135);
FORCEPROP 1 LASTPIN (25 125) BN 9
J 2
(37 133);
DISPLAY 0.680851 (37 133);
PAINT GREEN (37 133);
FORCEPROP 2 LAST CDS_LIB standard
J 0
(-25 125);
DISPLAY INVISIBLE (-25 125);
FORCEPROP 1 LAST BODY_TYPE PLUMBING
J 2
(-25 175);
DISPLAY 0.872340 (-25 175);
PAINT GREEN (-25 175);
DISPLAY INVISIBLE (-25 175);
FORCEPROP 1 LAST HDL_TAP TRUE
J 2
(-350 0);
DISPLAY 0.872340 (-350 0);
DISPLAY INVISIBLE (-350 0);
FORCEPROP 1 LAST PATH I340
J 2
(-23 125);
DISPLAY 0.872340 (-23 125);
PAINT GREEN (-23 125);
DISPLAY INVISIBLE (-23 125);
FORCEADD TAP..1
R 2
(-25 1275);
FORCEPROP 3 LASTPIN (25 1275) SIG_NAME P5E_CPU1_PE1_RX_DP<15>
J 0
(35 1285);
DISPLAY 0.659574 (35 1285);
PAINT MONO (35 1285);
DISPLAY INVISIBLE (35 1285);
FORCEPROP 1 LASTPIN (25 1275) BN 15
J 2
(37 1283);
DISPLAY 0.680851 (37 1283);
PAINT GREEN (37 1283);
FORCEPROP 2 LAST CDS_LIB standard
J 0
(-25 1275);
DISPLAY INVISIBLE (-25 1275);
FORCEPROP 1 LAST BODY_TYPE PLUMBING
J 2
(-25 1325);
DISPLAY 0.872340 (-25 1325);
PAINT GREEN (-25 1325);
DISPLAY INVISIBLE (-25 1325);
FORCEPROP 1 LAST HDL_TAP TRUE
J 2
(-350 1150);
DISPLAY 0.872340 (-350 1150);
DISPLAY INVISIBLE (-350 1150);
FORCEPROP 1 LAST PATH I341
J 2
(-23 1275);
DISPLAY 0.872340 (-23 1275);
PAINT GREEN (-23 1275);
DISPLAY INVISIBLE (-23 1275);
FORCEADD TAP..1
R 2
(-25 1225);
FORCEPROP 3 LASTPIN (25 1225) SIG_NAME P5E_CPU1_PE1_RX_DP<14>
J 0
(35 1235);
DISPLAY 0.659574 (35 1235);
PAINT MONO (35 1235);
DISPLAY INVISIBLE (35 1235);
FORCEPROP 1 LASTPIN (25 1225) BN 14
J 2
(37 1233);
DISPLAY 0.680851 (37 1233);
PAINT GREEN (37 1233);
FORCEPROP 2 LAST CDS_LIB standard
J 0
(-25 1225);
DISPLAY INVISIBLE (-25 1225);
FORCEPROP 1 LAST BODY_TYPE PLUMBING
J 2
(-25 1275);
DISPLAY 0.872340 (-25 1275);
PAINT GREEN (-25 1275);
DISPLAY INVISIBLE (-25 1275);
FORCEPROP 1 LAST HDL_TAP TRUE
J 2
(-350 1100);
DISPLAY 0.872340 (-350 1100);
DISPLAY INVISIBLE (-350 1100);
FORCEPROP 1 LAST PATH I342
J 2
(-23 1225);
DISPLAY 0.872340 (-23 1225);
PAINT GREEN (-23 1225);
DISPLAY INVISIBLE (-23 1225);
FORCEADD TAP..1
R 2
(-25 1175);
FORCEPROP 3 LASTPIN (25 1175) SIG_NAME P5E_CPU1_PE1_RX_DP<13>
J 0
(35 1185);
DISPLAY 0.659574 (35 1185);
PAINT MONO (35 1185);
DISPLAY INVISIBLE (35 1185);
FORCEPROP 1 LASTPIN (25 1175) BN 13
J 2
(37 1183);
DISPLAY 0.680851 (37 1183);
PAINT GREEN (37 1183);
FORCEPROP 2 LAST CDS_LIB standard
J 0
(-25 1175);
DISPLAY INVISIBLE (-25 1175);
FORCEPROP 1 LAST BODY_TYPE PLUMBING
J 2
(-25 1225);
DISPLAY 0.872340 (-25 1225);
PAINT GREEN (-25 1225);
DISPLAY INVISIBLE (-25 1225);
FORCEPROP 1 LAST HDL_TAP TRUE
J 2
(-350 1050);
DISPLAY 0.872340 (-350 1050);
DISPLAY INVISIBLE (-350 1050);
FORCEPROP 1 LAST PATH I343
J 2
(-23 1175);
DISPLAY 0.872340 (-23 1175);
PAINT GREEN (-23 1175);
DISPLAY INVISIBLE (-23 1175);
FORCEADD TAP..1
R 2
(-25 1125);
FORCEPROP 3 LASTPIN (25 1125) SIG_NAME P5E_CPU1_PE1_RX_DP<12>
J 0
(35 1135);
DISPLAY 0.659574 (35 1135);
PAINT MONO (35 1135);
DISPLAY INVISIBLE (35 1135);
FORCEPROP 1 LASTPIN (25 1125) BN 12
J 2
(37 1133);
DISPLAY 0.680851 (37 1133);
PAINT GREEN (37 1133);
FORCEPROP 2 LAST CDS_LIB standard
J 0
(-25 1125);
DISPLAY INVISIBLE (-25 1125);
FORCEPROP 1 LAST BODY_TYPE PLUMBING
J 2
(-25 1175);
DISPLAY 0.872340 (-25 1175);
PAINT GREEN (-25 1175);
DISPLAY INVISIBLE (-25 1175);
FORCEPROP 1 LAST HDL_TAP TRUE
J 2
(-350 1000);
DISPLAY 0.872340 (-350 1000);
DISPLAY INVISIBLE (-350 1000);
FORCEPROP 1 LAST PATH I344
J 2
(-23 1125);
DISPLAY 0.872340 (-23 1125);
PAINT GREEN (-23 1125);
DISPLAY INVISIBLE (-23 1125);
FORCEADD TAP..1
R 2
(-25 1075);
FORCEPROP 3 LASTPIN (25 1075) SIG_NAME P5E_CPU1_PE1_RX_DP<11>
J 0
(35 1085);
DISPLAY 0.659574 (35 1085);
PAINT MONO (35 1085);
DISPLAY INVISIBLE (35 1085);
FORCEPROP 1 LASTPIN (25 1075) BN 11
J 2
(37 1083);
DISPLAY 0.680851 (37 1083);
PAINT GREEN (37 1083);
FORCEPROP 2 LAST CDS_LIB standard
J 0
(-25 1075);
DISPLAY INVISIBLE (-25 1075);
FORCEPROP 1 LAST BODY_TYPE PLUMBING
J 2
(-25 1125);
DISPLAY 0.872340 (-25 1125);
PAINT GREEN (-25 1125);
DISPLAY INVISIBLE (-25 1125);
FORCEPROP 1 LAST HDL_TAP TRUE
J 2
(-350 950);
DISPLAY 0.872340 (-350 950);
DISPLAY INVISIBLE (-350 950);
FORCEPROP 1 LAST PATH I345
J 2
(-23 1075);
DISPLAY 0.872340 (-23 1075);
PAINT GREEN (-23 1075);
DISPLAY INVISIBLE (-23 1075);
FORCEADD TAP..1
R 2
(-25 1025);
FORCEPROP 3 LASTPIN (25 1025) SIG_NAME P5E_CPU1_PE1_RX_DP<10>
J 0
(35 1035);
DISPLAY 0.659574 (35 1035);
PAINT MONO (35 1035);
DISPLAY INVISIBLE (35 1035);
FORCEPROP 1 LASTPIN (25 1025) BN 10
J 2
(37 1033);
DISPLAY 0.680851 (37 1033);
PAINT GREEN (37 1033);
FORCEPROP 2 LAST CDS_LIB standard
J 0
(-25 1025);
DISPLAY INVISIBLE (-25 1025);
FORCEPROP 1 LAST BODY_TYPE PLUMBING
J 2
(-25 1075);
DISPLAY 0.872340 (-25 1075);
PAINT GREEN (-25 1075);
DISPLAY INVISIBLE (-25 1075);
FORCEPROP 1 LAST HDL_TAP TRUE
J 2
(-350 900);
DISPLAY 0.872340 (-350 900);
DISPLAY INVISIBLE (-350 900);
FORCEPROP 1 LAST PATH I346
J 2
(-23 1025);
DISPLAY 0.872340 (-23 1025);
PAINT GREEN (-23 1025);
DISPLAY INVISIBLE (-23 1025);
FORCEADD TAP..1
R 2
(-25 975);
FORCEPROP 3 LASTPIN (25 975) SIG_NAME P5E_CPU1_PE1_RX_DP<9>
J 0
(35 985);
DISPLAY 0.659574 (35 985);
PAINT MONO (35 985);
DISPLAY INVISIBLE (35 985);
FORCEPROP 1 LASTPIN (25 975) BN 9
J 2
(37 983);
DISPLAY 0.680851 (37 983);
PAINT GREEN (37 983);
FORCEPROP 2 LAST CDS_LIB standard
J 0
(-25 975);
DISPLAY INVISIBLE (-25 975);
FORCEPROP 1 LAST BODY_TYPE PLUMBING
J 2
(-25 1025);
DISPLAY 0.872340 (-25 1025);
PAINT GREEN (-25 1025);
DISPLAY INVISIBLE (-25 1025);
FORCEPROP 1 LAST HDL_TAP TRUE
J 2
(-350 850);
DISPLAY 0.872340 (-350 850);
DISPLAY INVISIBLE (-350 850);
FORCEPROP 1 LAST PATH I347
J 2
(-23 975);
DISPLAY 0.872340 (-23 975);
PAINT GREEN (-23 975);
DISPLAY INVISIBLE (-23 975);
FORCEADD TAP..1
R 2
(-25 925);
FORCEPROP 3 LASTPIN (25 925) SIG_NAME P5E_CPU1_PE1_RX_DP<8>
J 0
(35 935);
DISPLAY 0.659574 (35 935);
PAINT MONO (35 935);
DISPLAY INVISIBLE (35 935);
FORCEPROP 1 LASTPIN (25 925) BN 8
J 2
(37 933);
DISPLAY 0.680851 (37 933);
PAINT GREEN (37 933);
FORCEPROP 2 LAST CDS_LIB standard
J 0
(-25 925);
DISPLAY INVISIBLE (-25 925);
FORCEPROP 1 LAST BODY_TYPE PLUMBING
J 2
(-25 975);
DISPLAY 0.872340 (-25 975);
PAINT GREEN (-25 975);
DISPLAY INVISIBLE (-25 975);
FORCEPROP 1 LAST HDL_TAP TRUE
J 2
(-350 800);
DISPLAY 0.872340 (-350 800);
DISPLAY INVISIBLE (-350 800);
FORCEPROP 1 LAST PATH I348
J 2
(-23 925);
DISPLAY 0.872340 (-23 925);
PAINT GREEN (-23 925);
DISPLAY INVISIBLE (-23 925);
FORCEADD TAP..1
R 2
(-25 825);
FORCEPROP 3 LASTPIN (25 825) SIG_NAME P5E_CPU1_PE1_RX_DP<6>
J 0
(35 835);
DISPLAY 0.659574 (35 835);
PAINT MONO (35 835);
DISPLAY INVISIBLE (35 835);
FORCEPROP 1 LASTPIN (25 825) BN 6
J 2
(37 833);
DISPLAY 0.680851 (37 833);
PAINT GREEN (37 833);
FORCEPROP 2 LAST CDS_LIB standard
J 0
(-25 825);
DISPLAY INVISIBLE (-25 825);
FORCEPROP 1 LAST BODY_TYPE PLUMBING
J 2
(-25 875);
DISPLAY 0.872340 (-25 875);
PAINT GREEN (-25 875);
DISPLAY INVISIBLE (-25 875);
FORCEPROP 1 LAST HDL_TAP TRUE
J 2
(-350 700);
DISPLAY 0.872340 (-350 700);
DISPLAY INVISIBLE (-350 700);
FORCEPROP 1 LAST PATH I349
J 2
(-23 825);
DISPLAY 0.872340 (-23 825);
PAINT GREEN (-23 825);
DISPLAY INVISIBLE (-23 825);
FORCEADD TAP..1
R 2
(-25 875);
FORCEPROP 3 LASTPIN (25 875) SIG_NAME P5E_CPU1_PE1_RX_DP<7>
J 0
(35 885);
DISPLAY 0.659574 (35 885);
PAINT MONO (35 885);
DISPLAY INVISIBLE (35 885);
FORCEPROP 1 LASTPIN (25 875) BN 7
J 2
(37 883);
DISPLAY 0.680851 (37 883);
PAINT GREEN (37 883);
FORCEPROP 2 LAST CDS_LIB standard
J 0
(-25 875);
DISPLAY INVISIBLE (-25 875);
FORCEPROP 1 LAST BODY_TYPE PLUMBING
J 2
(-25 925);
DISPLAY 0.872340 (-25 925);
PAINT GREEN (-25 925);
DISPLAY INVISIBLE (-25 925);
FORCEPROP 1 LAST HDL_TAP TRUE
J 2
(-350 750);
DISPLAY 0.872340 (-350 750);
DISPLAY INVISIBLE (-350 750);
FORCEPROP 1 LAST PATH I350
J 2
(-23 875);
DISPLAY 0.872340 (-23 875);
PAINT GREEN (-23 875);
DISPLAY INVISIBLE (-23 875);
FORCEADD TAP..1
R 2
(-25 725);
FORCEPROP 3 LASTPIN (25 725) SIG_NAME P5E_CPU1_PE1_RX_DP<4>
J 0
(35 735);
DISPLAY 0.659574 (35 735);
PAINT MONO (35 735);
DISPLAY INVISIBLE (35 735);
FORCEPROP 1 LASTPIN (25 725) BN 4
J 2
(37 733);
DISPLAY 0.680851 (37 733);
PAINT GREEN (37 733);
FORCEPROP 2 LAST CDS_LIB standard
J 0
(-25 725);
DISPLAY INVISIBLE (-25 725);
FORCEPROP 1 LAST BODY_TYPE PLUMBING
J 2
(-25 775);
DISPLAY 0.872340 (-25 775);
PAINT GREEN (-25 775);
DISPLAY INVISIBLE (-25 775);
FORCEPROP 1 LAST HDL_TAP TRUE
J 2
(-350 600);
DISPLAY 0.872340 (-350 600);
DISPLAY INVISIBLE (-350 600);
FORCEPROP 1 LAST PATH I351
J 2
(-23 725);
DISPLAY 0.872340 (-23 725);
PAINT GREEN (-23 725);
DISPLAY INVISIBLE (-23 725);
FORCEADD TAP..1
R 2
(-25 775);
FORCEPROP 3 LASTPIN (25 775) SIG_NAME P5E_CPU1_PE1_RX_DP<5>
J 0
(35 785);
DISPLAY 0.659574 (35 785);
PAINT MONO (35 785);
DISPLAY INVISIBLE (35 785);
FORCEPROP 1 LASTPIN (25 775) BN 5
J 2
(37 783);
DISPLAY 0.680851 (37 783);
PAINT GREEN (37 783);
FORCEPROP 2 LAST CDS_LIB standard
J 0
(-25 775);
DISPLAY INVISIBLE (-25 775);
FORCEPROP 1 LAST BODY_TYPE PLUMBING
J 2
(-25 825);
DISPLAY 0.872340 (-25 825);
PAINT GREEN (-25 825);
DISPLAY INVISIBLE (-25 825);
FORCEPROP 1 LAST HDL_TAP TRUE
J 2
(-350 650);
DISPLAY 0.872340 (-350 650);
DISPLAY INVISIBLE (-350 650);
FORCEPROP 1 LAST PATH I352
J 2
(-23 775);
DISPLAY 0.872340 (-23 775);
PAINT GREEN (-23 775);
DISPLAY INVISIBLE (-23 775);
FORCEADD TAP..1
R 2
(-25 675);
FORCEPROP 3 LASTPIN (25 675) SIG_NAME P5E_CPU1_PE1_RX_DP<3>
J 0
(35 685);
DISPLAY 0.659574 (35 685);
PAINT MONO (35 685);
DISPLAY INVISIBLE (35 685);
FORCEPROP 1 LASTPIN (25 675) BN 3
J 2
(37 683);
DISPLAY 0.680851 (37 683);
PAINT GREEN (37 683);
FORCEPROP 2 LAST CDS_LIB standard
J 0
(-25 675);
DISPLAY INVISIBLE (-25 675);
FORCEPROP 1 LAST BODY_TYPE PLUMBING
J 2
(-25 725);
DISPLAY 0.872340 (-25 725);
PAINT GREEN (-25 725);
DISPLAY INVISIBLE (-25 725);
FORCEPROP 1 LAST HDL_TAP TRUE
J 2
(-350 550);
DISPLAY 0.872340 (-350 550);
DISPLAY INVISIBLE (-350 550);
FORCEPROP 1 LAST PATH I353
J 2
(-23 675);
DISPLAY 0.872340 (-23 675);
PAINT GREEN (-23 675);
DISPLAY INVISIBLE (-23 675);
FORCEADD TAP..1
R 2
(-25 575);
FORCEPROP 3 LASTPIN (25 575) SIG_NAME P5E_CPU1_PE1_RX_DP<1>
J 0
(35 585);
DISPLAY 0.659574 (35 585);
PAINT MONO (35 585);
DISPLAY INVISIBLE (35 585);
FORCEPROP 1 LASTPIN (25 575) BN 1
J 2
(37 583);
DISPLAY 0.680851 (37 583);
PAINT GREEN (37 583);
FORCEPROP 2 LAST CDS_LIB standard
J 0
(-25 575);
DISPLAY INVISIBLE (-25 575);
FORCEPROP 1 LAST BODY_TYPE PLUMBING
J 2
(-25 625);
DISPLAY 0.872340 (-25 625);
PAINT GREEN (-25 625);
DISPLAY INVISIBLE (-25 625);
FORCEPROP 1 LAST HDL_TAP TRUE
J 2
(-350 450);
DISPLAY 0.872340 (-350 450);
DISPLAY INVISIBLE (-350 450);
FORCEPROP 1 LAST PATH I354
J 2
(-23 575);
DISPLAY 0.872340 (-23 575);
PAINT GREEN (-23 575);
DISPLAY INVISIBLE (-23 575);
FORCEADD TAP..1
R 2
(-25 625);
FORCEPROP 3 LASTPIN (25 625) SIG_NAME P5E_CPU1_PE1_RX_DP<2>
J 0
(35 635);
DISPLAY 0.659574 (35 635);
PAINT MONO (35 635);
DISPLAY INVISIBLE (35 635);
FORCEPROP 1 LASTPIN (25 625) BN 2
J 2
(37 633);
DISPLAY 0.680851 (37 633);
PAINT GREEN (37 633);
FORCEPROP 2 LAST CDS_LIB standard
J 0
(-25 625);
DISPLAY INVISIBLE (-25 625);
FORCEPROP 1 LAST BODY_TYPE PLUMBING
J 2
(-25 675);
DISPLAY 0.872340 (-25 675);
PAINT GREEN (-25 675);
DISPLAY INVISIBLE (-25 675);
FORCEPROP 1 LAST HDL_TAP TRUE
J 2
(-350 500);
DISPLAY 0.872340 (-350 500);
DISPLAY INVISIBLE (-350 500);
FORCEPROP 1 LAST PATH I355
J 2
(-23 625);
DISPLAY 0.872340 (-23 625);
PAINT GREEN (-23 625);
DISPLAY INVISIBLE (-23 625);
FORCEADD TAP..1
R 2
(-25 525);
FORCEPROP 3 LASTPIN (25 525) SIG_NAME P5E_CPU1_PE1_RX_DP<0>
J 0
(35 535);
DISPLAY 0.659574 (35 535);
PAINT MONO (35 535);
DISPLAY INVISIBLE (35 535);
FORCEPROP 1 LASTPIN (25 525) BN 0
J 2
(37 533);
DISPLAY 0.680851 (37 533);
PAINT GREEN (37 533);
FORCEPROP 2 LAST CDS_LIB standard
J 0
(-25 525);
DISPLAY INVISIBLE (-25 525);
FORCEPROP 1 LAST BODY_TYPE PLUMBING
J 2
(-25 575);
DISPLAY 0.872340 (-25 575);
PAINT GREEN (-25 575);
DISPLAY INVISIBLE (-25 575);
FORCEPROP 1 LAST HDL_TAP TRUE
J 2
(-350 400);
DISPLAY 0.872340 (-350 400);
DISPLAY INVISIBLE (-350 400);
FORCEPROP 1 LAST PATH I356
J 2
(-23 525);
DISPLAY 0.872340 (-23 525);
PAINT GREEN (-23 525);
DISPLAY INVISIBLE (-23 525);
FORCEADD TAP..1
R 2
(-25 425);
FORCEPROP 3 LASTPIN (25 425) SIG_NAME P5E_CPU1_PE1_RX_DN<15>
J 0
(35 435);
DISPLAY 0.659574 (35 435);
PAINT MONO (35 435);
DISPLAY INVISIBLE (35 435);
FORCEPROP 1 LASTPIN (25 425) BN 15
J 2
(37 433);
DISPLAY 0.680851 (37 433);
PAINT GREEN (37 433);
FORCEPROP 2 LAST CDS_LIB standard
J 0
(-25 425);
DISPLAY INVISIBLE (-25 425);
FORCEPROP 1 LAST BODY_TYPE PLUMBING
J 2
(-25 475);
DISPLAY 0.872340 (-25 475);
PAINT GREEN (-25 475);
DISPLAY INVISIBLE (-25 475);
FORCEPROP 1 LAST HDL_TAP TRUE
J 2
(-350 300);
DISPLAY 0.872340 (-350 300);
DISPLAY INVISIBLE (-350 300);
FORCEPROP 1 LAST PATH I357
J 2
(-23 425);
DISPLAY 0.872340 (-23 425);
PAINT GREEN (-23 425);
DISPLAY INVISIBLE (-23 425);
FORCEADD TAP..1
R 2
(-25 375);
FORCEPROP 3 LASTPIN (25 375) SIG_NAME P5E_CPU1_PE1_RX_DN<14>
J 0
(35 385);
DISPLAY 0.659574 (35 385);
PAINT MONO (35 385);
DISPLAY INVISIBLE (35 385);
FORCEPROP 1 LASTPIN (25 375) BN 14
J 2
(37 383);
DISPLAY 0.680851 (37 383);
PAINT GREEN (37 383);
FORCEPROP 2 LAST CDS_LIB standard
J 0
(-25 375);
DISPLAY INVISIBLE (-25 375);
FORCEPROP 1 LAST BODY_TYPE PLUMBING
J 2
(-25 425);
DISPLAY 0.872340 (-25 425);
PAINT GREEN (-25 425);
DISPLAY INVISIBLE (-25 425);
FORCEPROP 1 LAST HDL_TAP TRUE
J 2
(-350 250);
DISPLAY 0.872340 (-350 250);
DISPLAY INVISIBLE (-350 250);
FORCEPROP 1 LAST PATH I358
J 2
(-23 375);
DISPLAY 0.872340 (-23 375);
PAINT GREEN (-23 375);
DISPLAY INVISIBLE (-23 375);
FORCEADD TAP..1
R 2
(-25 325);
FORCEPROP 3 LASTPIN (25 325) SIG_NAME P5E_CPU1_PE1_RX_DN<13>
J 0
(35 335);
DISPLAY 0.659574 (35 335);
PAINT MONO (35 335);
DISPLAY INVISIBLE (35 335);
FORCEPROP 1 LASTPIN (25 325) BN 13
J 2
(37 333);
DISPLAY 0.680851 (37 333);
PAINT GREEN (37 333);
FORCEPROP 2 LAST CDS_LIB standard
J 0
(-25 325);
DISPLAY INVISIBLE (-25 325);
FORCEPROP 1 LAST BODY_TYPE PLUMBING
J 2
(-25 375);
DISPLAY 0.872340 (-25 375);
PAINT GREEN (-25 375);
DISPLAY INVISIBLE (-25 375);
FORCEPROP 1 LAST HDL_TAP TRUE
J 2
(-350 200);
DISPLAY 0.872340 (-350 200);
DISPLAY INVISIBLE (-350 200);
FORCEPROP 1 LAST PATH I359
J 2
(-23 325);
DISPLAY 0.872340 (-23 325);
PAINT GREEN (-23 325);
DISPLAY INVISIBLE (-23 325);
FORCEADD TAP..1
R 2
(-25 275);
FORCEPROP 3 LASTPIN (25 275) SIG_NAME P5E_CPU1_PE1_RX_DN<12>
J 0
(35 285);
DISPLAY 0.659574 (35 285);
PAINT MONO (35 285);
DISPLAY INVISIBLE (35 285);
FORCEPROP 1 LASTPIN (25 275) BN 12
J 2
(37 283);
DISPLAY 0.680851 (37 283);
PAINT GREEN (37 283);
FORCEPROP 2 LAST CDS_LIB standard
J 0
(-25 275);
DISPLAY INVISIBLE (-25 275);
FORCEPROP 1 LAST BODY_TYPE PLUMBING
J 2
(-25 325);
DISPLAY 0.872340 (-25 325);
PAINT GREEN (-25 325);
DISPLAY INVISIBLE (-25 325);
FORCEPROP 1 LAST HDL_TAP TRUE
J 2
(-350 150);
DISPLAY 0.872340 (-350 150);
DISPLAY INVISIBLE (-350 150);
FORCEPROP 1 LAST PATH I360
J 2
(-23 275);
DISPLAY 0.872340 (-23 275);
PAINT GREEN (-23 275);
DISPLAY INVISIBLE (-23 275);
FORCEADD TAP..1
R 2
(-25 75);
FORCEPROP 3 LASTPIN (25 75) SIG_NAME P5E_CPU1_PE1_RX_DN<8>
J 0
(35 85);
DISPLAY 0.659574 (35 85);
PAINT MONO (35 85);
DISPLAY INVISIBLE (35 85);
FORCEPROP 1 LASTPIN (25 75) BN 8
J 2
(37 83);
DISPLAY 0.680851 (37 83);
PAINT GREEN (37 83);
FORCEPROP 2 LAST CDS_LIB standard
J 0
(-25 75);
DISPLAY INVISIBLE (-25 75);
FORCEPROP 1 LAST BODY_TYPE PLUMBING
J 2
(-25 125);
DISPLAY 0.872340 (-25 125);
PAINT GREEN (-25 125);
DISPLAY INVISIBLE (-25 125);
FORCEPROP 1 LAST HDL_TAP TRUE
J 2
(-350 -50);
DISPLAY 0.872340 (-350 -50);
DISPLAY INVISIBLE (-350 -50);
FORCEPROP 1 LAST PATH I361
J 2
(-23 75);
DISPLAY 0.872340 (-23 75);
PAINT GREEN (-23 75);
DISPLAY INVISIBLE (-23 75);
FORCEADD TAP..1
R 2
(-25 -75);
FORCEPROP 3 LASTPIN (25 -75) SIG_NAME P5E_CPU1_PE1_RX_DN<5>
J 0
(35 -65);
DISPLAY 0.659574 (35 -65);
PAINT MONO (35 -65);
DISPLAY INVISIBLE (35 -65);
FORCEPROP 1 LASTPIN (25 -75) BN 5
J 2
(37 -67);
DISPLAY 0.680851 (37 -67);
PAINT GREEN (37 -67);
FORCEPROP 2 LAST CDS_LIB standard
J 0
(-25 -75);
DISPLAY INVISIBLE (-25 -75);
FORCEPROP 1 LAST BODY_TYPE PLUMBING
J 2
(-25 -25);
DISPLAY 0.872340 (-25 -25);
PAINT GREEN (-25 -25);
DISPLAY INVISIBLE (-25 -25);
FORCEPROP 1 LAST HDL_TAP TRUE
J 2
(-350 -200);
DISPLAY 0.872340 (-350 -200);
DISPLAY INVISIBLE (-350 -200);
FORCEPROP 1 LAST PATH I362
J 2
(-23 -75);
DISPLAY 0.872340 (-23 -75);
PAINT GREEN (-23 -75);
DISPLAY INVISIBLE (-23 -75);
FORCEADD TAP..1
R 2
(-25 25);
FORCEPROP 3 LASTPIN (25 25) SIG_NAME P5E_CPU1_PE1_RX_DN<7>
J 0
(35 35);
DISPLAY 0.659574 (35 35);
PAINT MONO (35 35);
DISPLAY INVISIBLE (35 35);
FORCEPROP 1 LASTPIN (25 25) BN 7
J 2
(37 33);
DISPLAY 0.680851 (37 33);
PAINT GREEN (37 33);
FORCEPROP 2 LAST CDS_LIB standard
J 0
(-25 25);
DISPLAY INVISIBLE (-25 25);
FORCEPROP 1 LAST BODY_TYPE PLUMBING
J 2
(-25 75);
DISPLAY 0.872340 (-25 75);
PAINT GREEN (-25 75);
DISPLAY INVISIBLE (-25 75);
FORCEPROP 1 LAST HDL_TAP TRUE
J 2
(-350 -100);
DISPLAY 0.872340 (-350 -100);
DISPLAY INVISIBLE (-350 -100);
FORCEPROP 1 LAST PATH I363
J 2
(-23 25);
DISPLAY 0.872340 (-23 25);
PAINT GREEN (-23 25);
DISPLAY INVISIBLE (-23 25);
FORCEADD TAP..1
R 2
(-25 -25);
FORCEPROP 3 LASTPIN (25 -25) SIG_NAME P5E_CPU1_PE1_RX_DN<6>
J 0
(35 -15);
DISPLAY 0.659574 (35 -15);
PAINT MONO (35 -15);
DISPLAY INVISIBLE (35 -15);
FORCEPROP 1 LASTPIN (25 -25) BN 6
J 2
(37 -17);
DISPLAY 0.680851 (37 -17);
PAINT GREEN (37 -17);
FORCEPROP 2 LAST CDS_LIB standard
J 0
(-25 -25);
DISPLAY INVISIBLE (-25 -25);
FORCEPROP 1 LAST BODY_TYPE PLUMBING
J 2
(-25 25);
DISPLAY 0.872340 (-25 25);
PAINT GREEN (-25 25);
DISPLAY INVISIBLE (-25 25);
FORCEPROP 1 LAST HDL_TAP TRUE
J 2
(-350 -150);
DISPLAY 0.872340 (-350 -150);
DISPLAY INVISIBLE (-350 -150);
FORCEPROP 1 LAST PATH I364
J 2
(-23 -25);
DISPLAY 0.872340 (-23 -25);
PAINT GREEN (-23 -25);
DISPLAY INVISIBLE (-23 -25);
FORCEADD TAP..1
R 2
(-25 -125);
FORCEPROP 3 LASTPIN (25 -125) SIG_NAME P5E_CPU1_PE1_RX_DN<4>
J 0
(35 -115);
DISPLAY 0.659574 (35 -115);
PAINT MONO (35 -115);
DISPLAY INVISIBLE (35 -115);
FORCEPROP 1 LASTPIN (25 -125) BN 4
J 2
(37 -117);
DISPLAY 0.680851 (37 -117);
PAINT GREEN (37 -117);
FORCEPROP 2 LAST CDS_LIB standard
J 0
(-25 -125);
DISPLAY INVISIBLE (-25 -125);
FORCEPROP 1 LAST BODY_TYPE PLUMBING
J 2
(-25 -75);
DISPLAY 0.872340 (-25 -75);
PAINT GREEN (-25 -75);
DISPLAY INVISIBLE (-25 -75);
FORCEPROP 1 LAST HDL_TAP TRUE
J 2
(-350 -250);
DISPLAY 0.872340 (-350 -250);
DISPLAY INVISIBLE (-350 -250);
FORCEPROP 1 LAST PATH I365
J 2
(-23 -125);
DISPLAY 0.872340 (-23 -125);
PAINT GREEN (-23 -125);
DISPLAY INVISIBLE (-23 -125);
FORCEADD TAP..1
R 2
(-25 -175);
FORCEPROP 3 LASTPIN (25 -175) SIG_NAME P5E_CPU1_PE1_RX_DN<3>
J 0
(35 -165);
DISPLAY 0.659574 (35 -165);
PAINT MONO (35 -165);
DISPLAY INVISIBLE (35 -165);
FORCEPROP 1 LASTPIN (25 -175) BN 3
J 2
(37 -167);
DISPLAY 0.680851 (37 -167);
PAINT GREEN (37 -167);
FORCEPROP 2 LAST CDS_LIB standard
J 0
(-25 -175);
DISPLAY INVISIBLE (-25 -175);
FORCEPROP 1 LAST BODY_TYPE PLUMBING
J 2
(-25 -125);
DISPLAY 0.872340 (-25 -125);
PAINT GREEN (-25 -125);
DISPLAY INVISIBLE (-25 -125);
FORCEPROP 1 LAST HDL_TAP TRUE
J 2
(-350 -300);
DISPLAY 0.872340 (-350 -300);
DISPLAY INVISIBLE (-350 -300);
FORCEPROP 1 LAST PATH I366
J 2
(-23 -175);
DISPLAY 0.872340 (-23 -175);
PAINT GREEN (-23 -175);
DISPLAY INVISIBLE (-23 -175);
FORCEADD TAP..1
R 2
(-25 -275);
FORCEPROP 3 LASTPIN (25 -275) SIG_NAME P5E_CPU1_PE1_RX_DN<1>
J 0
(35 -265);
DISPLAY 0.659574 (35 -265);
PAINT MONO (35 -265);
DISPLAY INVISIBLE (35 -265);
FORCEPROP 1 LASTPIN (25 -275) BN 1
J 2
(37 -267);
DISPLAY 0.680851 (37 -267);
PAINT GREEN (37 -267);
FORCEPROP 2 LAST CDS_LIB standard
J 0
(-25 -275);
DISPLAY INVISIBLE (-25 -275);
FORCEPROP 1 LAST BODY_TYPE PLUMBING
J 2
(-25 -225);
DISPLAY 0.872340 (-25 -225);
PAINT GREEN (-25 -225);
DISPLAY INVISIBLE (-25 -225);
FORCEPROP 1 LAST HDL_TAP TRUE
J 2
(-350 -400);
DISPLAY 0.872340 (-350 -400);
DISPLAY INVISIBLE (-350 -400);
FORCEPROP 1 LAST PATH I367
J 2
(-23 -275);
DISPLAY 0.872340 (-23 -275);
PAINT GREEN (-23 -275);
DISPLAY INVISIBLE (-23 -275);
FORCEADD TAP..1
R 2
(-25 -225);
FORCEPROP 3 LASTPIN (25 -225) SIG_NAME P5E_CPU1_PE1_RX_DN<2>
J 0
(35 -215);
DISPLAY 0.659574 (35 -215);
PAINT MONO (35 -215);
DISPLAY INVISIBLE (35 -215);
FORCEPROP 1 LASTPIN (25 -225) BN 2
J 2
(37 -217);
DISPLAY 0.680851 (37 -217);
PAINT GREEN (37 -217);
FORCEPROP 2 LAST CDS_LIB standard
J 0
(-25 -225);
DISPLAY INVISIBLE (-25 -225);
FORCEPROP 1 LAST BODY_TYPE PLUMBING
J 2
(-25 -175);
DISPLAY 0.872340 (-25 -175);
PAINT GREEN (-25 -175);
DISPLAY INVISIBLE (-25 -175);
FORCEPROP 1 LAST HDL_TAP TRUE
J 2
(-350 -350);
DISPLAY 0.872340 (-350 -350);
DISPLAY INVISIBLE (-350 -350);
FORCEPROP 1 LAST PATH I368
J 2
(-23 -225);
DISPLAY 0.872340 (-23 -225);
PAINT GREEN (-23 -225);
DISPLAY INVISIBLE (-23 -225);
FORCEADD TAP..1
R 2
(-25 -325);
FORCEPROP 3 LASTPIN (25 -325) SIG_NAME P5E_CPU1_PE1_RX_DN<0>
J 0
(35 -315);
DISPLAY 0.659574 (35 -315);
PAINT MONO (35 -315);
DISPLAY INVISIBLE (35 -315);
FORCEPROP 1 LASTPIN (25 -325) BN 0
J 2
(37 -317);
DISPLAY 0.680851 (37 -317);
PAINT GREEN (37 -317);
FORCEPROP 2 LAST CDS_LIB standard
J 0
(-25 -325);
DISPLAY INVISIBLE (-25 -325);
FORCEPROP 1 LAST BODY_TYPE PLUMBING
J 2
(-25 -275);
DISPLAY 0.872340 (-25 -275);
PAINT GREEN (-25 -275);
DISPLAY INVISIBLE (-25 -275);
FORCEPROP 1 LAST HDL_TAP TRUE
J 2
(-350 -450);
DISPLAY 0.872340 (-350 -450);
DISPLAY INVISIBLE (-350 -450);
FORCEPROP 1 LAST PATH I369
J 2
(-23 -325);
DISPLAY 0.872340 (-23 -325);
PAINT GREEN (-23 -325);
DISPLAY INVISIBLE (-23 -325);
FORCEADD OFFPAGE..1
(-1275 1300);
FORCEPROP 2 LAST $XR0 159 
J 0
(-1527 1300);
DISPLAY 0.638298 (-1527 1300);
PAINT MONO (-1527 1300);
FORCEPROP 2 LAST CDS_LIB standard
J 0
(-1275 1300);
PAINT MONO (-1275 1300);
DISPLAY INVISIBLE (-1275 1300);
FORCEPROP 1 LAST OFFPAGE TRUE
J 0
(-950 1175);
DISPLAY 0.872340 (-950 1175);
DISPLAY INVISIBLE (-950 1175);
FORCEPROP 1 LAST COMMENT_BODY TRUE
J 0
(-1150 1200);
DISPLAY 0.872340 (-1150 1200);
PAINT GREEN (-1150 1200);
DISPLAY INVISIBLE (-1150 1200);
FORCEPROP 2 LAST PATH I370
J 0
(-1525 1350);
DISPLAY 1.021277 (-1525 1350);
DISPLAY INVISIBLE (-1525 1350);
FORCEADD OFFPAGE..1
(-1275 450);
FORCEPROP 2 LAST $XR0 159 
J 0
(-1527 450);
DISPLAY 0.638298 (-1527 450);
PAINT MONO (-1527 450);
FORCEPROP 2 LAST CDS_LIB standard
J 0
(-1275 450);
PAINT MONO (-1275 450);
DISPLAY INVISIBLE (-1275 450);
FORCEPROP 1 LAST OFFPAGE TRUE
J 0
(-950 325);
DISPLAY 0.872340 (-950 325);
DISPLAY INVISIBLE (-950 325);
FORCEPROP 1 LAST COMMENT_BODY TRUE
J 0
(-1150 350);
DISPLAY 0.872340 (-1150 350);
PAINT GREEN (-1150 350);
DISPLAY INVISIBLE (-1150 350);
FORCEPROP 2 LAST PATH I371
J 0
(-1525 500);
DISPLAY 1.021277 (-1525 500);
DISPLAY INVISIBLE (-1525 500);
FORCEADD TAP..1
(3400 -325);
FORCEPROP 3 LASTPIN (3350 -325) SIG_NAME P5E_CPU1_PE1_TX_DN<0>
J 0
(3360 -315);
DISPLAY 0.659574 (3360 -315);
PAINT MONO (3360 -315);
DISPLAY INVISIBLE (3360 -315);
FORCEPROP 1 LASTPIN (3350 -325) BN 0
J 0
(3338 -317);
DISPLAY 0.680851 (3338 -317);
PAINT GREEN (3338 -317);
FORCEPROP 2 LAST CDS_LIB standard
J 0
(3400 -325);
PAINT MONO (3400 -325);
DISPLAY INVISIBLE (3400 -325);
FORCEPROP 1 LAST BODY_TYPE PLUMBING
J 0
(3400 -275);
DISPLAY 0.872340 (3400 -275);
PAINT GREEN (3400 -275);
DISPLAY INVISIBLE (3400 -275);
FORCEPROP 1 LAST HDL_TAP TRUE
J 0
(3725 -450);
DISPLAY 0.872340 (3725 -450);
DISPLAY INVISIBLE (3725 -450);
FORCEPROP 1 LAST PATH I440
J 0
(3398 -325);
DISPLAY 0.872340 (3398 -325);
PAINT GREEN (3398 -325);
DISPLAY INVISIBLE (3398 -325);
FORCEADD TAP..1
(3400 -225);
FORCEPROP 3 LASTPIN (3350 -225) SIG_NAME P5E_CPU1_PE1_TX_DN<2>
J 0
(3360 -215);
DISPLAY 0.659574 (3360 -215);
PAINT MONO (3360 -215);
DISPLAY INVISIBLE (3360 -215);
FORCEPROP 1 LASTPIN (3350 -225) BN 2
J 0
(3338 -217);
DISPLAY 0.680851 (3338 -217);
PAINT GREEN (3338 -217);
FORCEPROP 2 LAST CDS_LIB standard
J 0
(3400 -225);
PAINT MONO (3400 -225);
DISPLAY INVISIBLE (3400 -225);
FORCEPROP 1 LAST BODY_TYPE PLUMBING
J 0
(3400 -175);
DISPLAY 0.872340 (3400 -175);
PAINT GREEN (3400 -175);
DISPLAY INVISIBLE (3400 -175);
FORCEPROP 1 LAST HDL_TAP TRUE
J 0
(3725 -350);
DISPLAY 0.872340 (3725 -350);
DISPLAY INVISIBLE (3725 -350);
FORCEPROP 1 LAST PATH I441
J 0
(3398 -225);
DISPLAY 0.872340 (3398 -225);
PAINT GREEN (3398 -225);
DISPLAY INVISIBLE (3398 -225);
FORCEADD TAP..1
(3400 -275);
FORCEPROP 3 LASTPIN (3350 -275) SIG_NAME P5E_CPU1_PE1_TX_DN<1>
J 0
(3360 -265);
DISPLAY 0.659574 (3360 -265);
PAINT MONO (3360 -265);
DISPLAY INVISIBLE (3360 -265);
FORCEPROP 1 LASTPIN (3350 -275) BN 1
J 0
(3338 -267);
DISPLAY 0.680851 (3338 -267);
PAINT GREEN (3338 -267);
FORCEPROP 2 LAST CDS_LIB standard
J 0
(3400 -275);
PAINT MONO (3400 -275);
DISPLAY INVISIBLE (3400 -275);
FORCEPROP 1 LAST BODY_TYPE PLUMBING
J 0
(3400 -225);
DISPLAY 0.872340 (3400 -225);
PAINT GREEN (3400 -225);
DISPLAY INVISIBLE (3400 -225);
FORCEPROP 1 LAST HDL_TAP TRUE
J 0
(3725 -400);
DISPLAY 0.872340 (3725 -400);
DISPLAY INVISIBLE (3725 -400);
FORCEPROP 1 LAST PATH I442
J 0
(3398 -275);
DISPLAY 0.872340 (3398 -275);
PAINT GREEN (3398 -275);
DISPLAY INVISIBLE (3398 -275);
FORCEADD TAP..1
(3400 -175);
FORCEPROP 3 LASTPIN (3350 -175) SIG_NAME P5E_CPU1_PE1_TX_DN<3>
J 0
(3360 -165);
DISPLAY 0.659574 (3360 -165);
PAINT MONO (3360 -165);
DISPLAY INVISIBLE (3360 -165);
FORCEPROP 1 LASTPIN (3350 -175) BN 3
J 0
(3338 -167);
DISPLAY 0.680851 (3338 -167);
PAINT GREEN (3338 -167);
FORCEPROP 2 LAST CDS_LIB standard
J 0
(3400 -175);
PAINT MONO (3400 -175);
DISPLAY INVISIBLE (3400 -175);
FORCEPROP 1 LAST BODY_TYPE PLUMBING
J 0
(3400 -125);
DISPLAY 0.872340 (3400 -125);
PAINT GREEN (3400 -125);
DISPLAY INVISIBLE (3400 -125);
FORCEPROP 1 LAST HDL_TAP TRUE
J 0
(3725 -300);
DISPLAY 0.872340 (3725 -300);
DISPLAY INVISIBLE (3725 -300);
FORCEPROP 1 LAST PATH I443
J 0
(3398 -175);
DISPLAY 0.872340 (3398 -175);
PAINT GREEN (3398 -175);
DISPLAY INVISIBLE (3398 -175);
FORCEADD TAP..1
(3400 -125);
FORCEPROP 3 LASTPIN (3350 -125) SIG_NAME P5E_CPU1_PE1_TX_DN<4>
J 0
(3360 -115);
DISPLAY 0.659574 (3360 -115);
PAINT MONO (3360 -115);
DISPLAY INVISIBLE (3360 -115);
FORCEPROP 1 LASTPIN (3350 -125) BN 4
J 0
(3338 -117);
DISPLAY 0.680851 (3338 -117);
PAINT GREEN (3338 -117);
FORCEPROP 2 LAST CDS_LIB standard
J 0
(3400 -125);
PAINT MONO (3400 -125);
DISPLAY INVISIBLE (3400 -125);
FORCEPROP 1 LAST BODY_TYPE PLUMBING
J 0
(3400 -75);
DISPLAY 0.872340 (3400 -75);
PAINT GREEN (3400 -75);
DISPLAY INVISIBLE (3400 -75);
FORCEPROP 1 LAST HDL_TAP TRUE
J 0
(3725 -250);
DISPLAY 0.872340 (3725 -250);
DISPLAY INVISIBLE (3725 -250);
FORCEPROP 1 LAST PATH I444
J 0
(3398 -125);
DISPLAY 0.872340 (3398 -125);
PAINT GREEN (3398 -125);
DISPLAY INVISIBLE (3398 -125);
FORCEADD TAP..1
(3400 25);
FORCEPROP 3 LASTPIN (3350 25) SIG_NAME P5E_CPU1_PE1_TX_DN<7>
J 0
(3360 35);
DISPLAY 0.659574 (3360 35);
PAINT MONO (3360 35);
DISPLAY INVISIBLE (3360 35);
FORCEPROP 1 LASTPIN (3350 25) BN 7
J 0
(3338 33);
DISPLAY 0.680851 (3338 33);
PAINT GREEN (3338 33);
FORCEPROP 2 LAST CDS_LIB standard
J 0
(3400 25);
PAINT MONO (3400 25);
DISPLAY INVISIBLE (3400 25);
FORCEPROP 1 LAST BODY_TYPE PLUMBING
J 0
(3400 75);
DISPLAY 0.872340 (3400 75);
PAINT GREEN (3400 75);
DISPLAY INVISIBLE (3400 75);
FORCEPROP 1 LAST HDL_TAP TRUE
J 0
(3725 -100);
DISPLAY 0.872340 (3725 -100);
DISPLAY INVISIBLE (3725 -100);
FORCEPROP 1 LAST PATH I445
J 0
(3398 25);
DISPLAY 0.872340 (3398 25);
PAINT GREEN (3398 25);
DISPLAY INVISIBLE (3398 25);
FORCEADD TAP..1
(3400 75);
FORCEPROP 3 LASTPIN (3350 75) SIG_NAME P5E_CPU1_PE1_TX_DN<8>
J 0
(3360 85);
DISPLAY 0.659574 (3360 85);
PAINT MONO (3360 85);
DISPLAY INVISIBLE (3360 85);
FORCEPROP 1 LASTPIN (3350 75) BN 8
J 0
(3338 83);
DISPLAY 0.680851 (3338 83);
PAINT GREEN (3338 83);
FORCEPROP 2 LAST CDS_LIB standard
J 0
(3400 75);
PAINT MONO (3400 75);
DISPLAY INVISIBLE (3400 75);
FORCEPROP 1 LAST BODY_TYPE PLUMBING
J 0
(3400 125);
DISPLAY 0.872340 (3400 125);
PAINT GREEN (3400 125);
DISPLAY INVISIBLE (3400 125);
FORCEPROP 1 LAST HDL_TAP TRUE
J 0
(3725 -50);
DISPLAY 0.872340 (3725 -50);
DISPLAY INVISIBLE (3725 -50);
FORCEPROP 1 LAST PATH I446
J 0
(3398 75);
DISPLAY 0.872340 (3398 75);
PAINT GREEN (3398 75);
DISPLAY INVISIBLE (3398 75);
FORCEADD TAP..1
(3400 175);
FORCEPROP 3 LASTPIN (3350 175) SIG_NAME P5E_CPU1_PE1_TX_DN<10>
J 0
(3360 185);
DISPLAY 0.659574 (3360 185);
PAINT MONO (3360 185);
DISPLAY INVISIBLE (3360 185);
FORCEPROP 1 LASTPIN (3350 175) BN 10
J 0
(3338 183);
DISPLAY 0.680851 (3338 183);
PAINT GREEN (3338 183);
FORCEPROP 2 LAST CDS_LIB standard
J 0
(3400 175);
DISPLAY INVISIBLE (3400 175);
FORCEPROP 1 LAST BODY_TYPE PLUMBING
J 0
(3400 225);
DISPLAY 0.872340 (3400 225);
PAINT GREEN (3400 225);
DISPLAY INVISIBLE (3400 225);
FORCEPROP 1 LAST HDL_TAP TRUE
J 0
(3725 50);
DISPLAY 0.872340 (3725 50);
DISPLAY INVISIBLE (3725 50);
FORCEPROP 1 LAST PATH I447
J 0
(3398 175);
DISPLAY 0.872340 (3398 175);
PAINT GREEN (3398 175);
DISPLAY INVISIBLE (3398 175);
FORCEADD TAP..1
(3400 125);
FORCEPROP 3 LASTPIN (3350 125) SIG_NAME P5E_CPU1_PE1_TX_DN<9>
J 0
(3360 135);
DISPLAY 0.659574 (3360 135);
PAINT MONO (3360 135);
DISPLAY INVISIBLE (3360 135);
FORCEPROP 1 LASTPIN (3350 125) BN 9
J 0
(3338 133);
DISPLAY 0.680851 (3338 133);
PAINT GREEN (3338 133);
FORCEPROP 2 LAST CDS_LIB standard
J 0
(3400 125);
DISPLAY INVISIBLE (3400 125);
FORCEPROP 1 LAST BODY_TYPE PLUMBING
J 0
(3400 175);
DISPLAY 0.872340 (3400 175);
PAINT GREEN (3400 175);
DISPLAY INVISIBLE (3400 175);
FORCEPROP 1 LAST HDL_TAP TRUE
J 0
(3725 0);
DISPLAY 0.872340 (3725 0);
DISPLAY INVISIBLE (3725 0);
FORCEPROP 1 LAST PATH I448
J 0
(3398 125);
DISPLAY 0.872340 (3398 125);
PAINT GREEN (3398 125);
DISPLAY INVISIBLE (3398 125);
FORCEADD TAP..1
(3400 325);
FORCEPROP 3 LASTPIN (3350 325) SIG_NAME P5E_CPU1_PE1_TX_DN<13>
J 0
(3360 335);
DISPLAY 0.659574 (3360 335);
PAINT MONO (3360 335);
DISPLAY INVISIBLE (3360 335);
FORCEPROP 1 LASTPIN (3350 325) BN 13
J 0
(3338 333);
DISPLAY 0.680851 (3338 333);
PAINT GREEN (3338 333);
FORCEPROP 2 LAST CDS_LIB standard
J 0
(3400 325);
DISPLAY INVISIBLE (3400 325);
FORCEPROP 1 LAST BODY_TYPE PLUMBING
J 0
(3400 375);
DISPLAY 0.872340 (3400 375);
PAINT GREEN (3400 375);
DISPLAY INVISIBLE (3400 375);
FORCEPROP 1 LAST HDL_TAP TRUE
J 0
(3725 200);
DISPLAY 0.872340 (3725 200);
DISPLAY INVISIBLE (3725 200);
FORCEPROP 1 LAST PATH I449
J 0
(3398 325);
DISPLAY 0.872340 (3398 325);
PAINT GREEN (3398 325);
DISPLAY INVISIBLE (3398 325);
FORCEADD TAP..1
(3400 275);
FORCEPROP 3 LASTPIN (3350 275) SIG_NAME P5E_CPU1_PE1_TX_DN<12>
J 0
(3360 285);
DISPLAY 0.659574 (3360 285);
PAINT MONO (3360 285);
DISPLAY INVISIBLE (3360 285);
FORCEPROP 1 LASTPIN (3350 275) BN 12
J 0
(3338 283);
DISPLAY 0.680851 (3338 283);
PAINT GREEN (3338 283);
FORCEPROP 2 LAST CDS_LIB standard
J 0
(3400 275);
DISPLAY INVISIBLE (3400 275);
FORCEPROP 1 LAST BODY_TYPE PLUMBING
J 0
(3400 325);
DISPLAY 0.872340 (3400 325);
PAINT GREEN (3400 325);
DISPLAY INVISIBLE (3400 325);
FORCEPROP 1 LAST HDL_TAP TRUE
J 0
(3725 150);
DISPLAY 0.872340 (3725 150);
DISPLAY INVISIBLE (3725 150);
FORCEPROP 1 LAST PATH I450
J 0
(3398 275);
DISPLAY 0.872340 (3398 275);
PAINT GREEN (3398 275);
DISPLAY INVISIBLE (3398 275);
FORCEADD TAP..1
(3400 225);
FORCEPROP 3 LASTPIN (3350 225) SIG_NAME P5E_CPU1_PE1_TX_DN<11>
J 0
(3360 235);
DISPLAY 0.659574 (3360 235);
PAINT MONO (3360 235);
DISPLAY INVISIBLE (3360 235);
FORCEPROP 1 LASTPIN (3350 225) BN 11
J 0
(3338 233);
DISPLAY 0.680851 (3338 233);
PAINT GREEN (3338 233);
FORCEPROP 2 LAST CDS_LIB standard
J 0
(3400 225);
DISPLAY INVISIBLE (3400 225);
FORCEPROP 1 LAST BODY_TYPE PLUMBING
J 0
(3400 275);
DISPLAY 0.872340 (3400 275);
PAINT GREEN (3400 275);
DISPLAY INVISIBLE (3400 275);
FORCEPROP 1 LAST HDL_TAP TRUE
J 0
(3725 100);
DISPLAY 0.872340 (3725 100);
DISPLAY INVISIBLE (3725 100);
FORCEPROP 1 LAST PATH I451
J 0
(3398 225);
DISPLAY 0.872340 (3398 225);
PAINT GREEN (3398 225);
DISPLAY INVISIBLE (3398 225);
FORCEADD TAP..1
(3400 425);
FORCEPROP 3 LASTPIN (3350 425) SIG_NAME P5E_CPU1_PE1_TX_DN<15>
J 0
(3360 435);
DISPLAY 0.659574 (3360 435);
PAINT MONO (3360 435);
DISPLAY INVISIBLE (3360 435);
FORCEPROP 1 LASTPIN (3350 425) BN 15
J 0
(3338 433);
DISPLAY 0.680851 (3338 433);
PAINT GREEN (3338 433);
FORCEPROP 2 LAST CDS_LIB standard
J 0
(3400 425);
DISPLAY INVISIBLE (3400 425);
FORCEPROP 1 LAST BODY_TYPE PLUMBING
J 0
(3400 475);
DISPLAY 0.872340 (3400 475);
PAINT GREEN (3400 475);
DISPLAY INVISIBLE (3400 475);
FORCEPROP 1 LAST HDL_TAP TRUE
J 0
(3725 300);
DISPLAY 0.872340 (3725 300);
DISPLAY INVISIBLE (3725 300);
FORCEPROP 1 LAST PATH I452
J 0
(3398 425);
DISPLAY 0.872340 (3398 425);
PAINT GREEN (3398 425);
DISPLAY INVISIBLE (3398 425);
FORCEADD TAP..1
(3400 375);
FORCEPROP 3 LASTPIN (3350 375) SIG_NAME P5E_CPU1_PE1_TX_DN<14>
J 0
(3360 385);
DISPLAY 0.659574 (3360 385);
PAINT MONO (3360 385);
DISPLAY INVISIBLE (3360 385);
FORCEPROP 1 LASTPIN (3350 375) BN 14
J 0
(3338 383);
DISPLAY 0.680851 (3338 383);
PAINT GREEN (3338 383);
FORCEPROP 2 LAST CDS_LIB standard
J 0
(3400 375);
DISPLAY INVISIBLE (3400 375);
FORCEPROP 1 LAST BODY_TYPE PLUMBING
J 0
(3400 425);
DISPLAY 0.872340 (3400 425);
PAINT GREEN (3400 425);
DISPLAY INVISIBLE (3400 425);
FORCEPROP 1 LAST HDL_TAP TRUE
J 0
(3725 250);
DISPLAY 0.872340 (3725 250);
DISPLAY INVISIBLE (3725 250);
FORCEPROP 1 LAST PATH I453
J 0
(3398 375);
DISPLAY 0.872340 (3398 375);
PAINT GREEN (3398 375);
DISPLAY INVISIBLE (3398 375);
FORCEADD TAP..1
(3400 525);
FORCEPROP 3 LASTPIN (3350 525) SIG_NAME P5E_CPU1_PE1_TX_DP<0>
J 0
(3360 535);
DISPLAY 0.659574 (3360 535);
PAINT MONO (3360 535);
DISPLAY INVISIBLE (3360 535);
FORCEPROP 1 LASTPIN (3350 525) BN 0
J 0
(3338 533);
DISPLAY 0.680851 (3338 533);
PAINT GREEN (3338 533);
FORCEPROP 2 LAST CDS_LIB standard
J 0
(3400 525);
PAINT MONO (3400 525);
DISPLAY INVISIBLE (3400 525);
FORCEPROP 1 LAST BODY_TYPE PLUMBING
J 0
(3400 575);
DISPLAY 0.872340 (3400 575);
PAINT GREEN (3400 575);
DISPLAY INVISIBLE (3400 575);
FORCEPROP 1 LAST HDL_TAP TRUE
J 0
(3725 400);
DISPLAY 0.872340 (3725 400);
DISPLAY INVISIBLE (3725 400);
FORCEPROP 1 LAST PATH I454
J 0
(3398 525);
DISPLAY 0.872340 (3398 525);
PAINT GREEN (3398 525);
DISPLAY INVISIBLE (3398 525);
FORCEADD TAP..1
(3400 575);
FORCEPROP 3 LASTPIN (3350 575) SIG_NAME P5E_CPU1_PE1_TX_DP<1>
J 0
(3360 585);
DISPLAY 0.659574 (3360 585);
PAINT MONO (3360 585);
DISPLAY INVISIBLE (3360 585);
FORCEPROP 1 LASTPIN (3350 575) BN 1
J 0
(3338 583);
DISPLAY 0.680851 (3338 583);
PAINT GREEN (3338 583);
FORCEPROP 2 LAST CDS_LIB standard
J 0
(3400 575);
PAINT MONO (3400 575);
DISPLAY INVISIBLE (3400 575);
FORCEPROP 1 LAST BODY_TYPE PLUMBING
J 0
(3400 625);
DISPLAY 0.872340 (3400 625);
PAINT GREEN (3400 625);
DISPLAY INVISIBLE (3400 625);
FORCEPROP 1 LAST HDL_TAP TRUE
J 0
(3725 450);
DISPLAY 0.872340 (3725 450);
DISPLAY INVISIBLE (3725 450);
FORCEPROP 1 LAST PATH I455
J 0
(3398 575);
DISPLAY 0.872340 (3398 575);
PAINT GREEN (3398 575);
DISPLAY INVISIBLE (3398 575);
FORCEADD TAP..1
(3400 675);
FORCEPROP 3 LASTPIN (3350 675) SIG_NAME P5E_CPU1_PE1_TX_DP<3>
J 0
(3360 685);
DISPLAY 0.659574 (3360 685);
PAINT MONO (3360 685);
DISPLAY INVISIBLE (3360 685);
FORCEPROP 1 LASTPIN (3350 675) BN 3
J 0
(3338 683);
DISPLAY 0.680851 (3338 683);
PAINT GREEN (3338 683);
FORCEPROP 2 LAST CDS_LIB standard
J 0
(3400 675);
PAINT MONO (3400 675);
DISPLAY INVISIBLE (3400 675);
FORCEPROP 1 LAST BODY_TYPE PLUMBING
J 0
(3400 725);
DISPLAY 0.872340 (3400 725);
PAINT GREEN (3400 725);
DISPLAY INVISIBLE (3400 725);
FORCEPROP 1 LAST HDL_TAP TRUE
J 0
(3725 550);
DISPLAY 0.872340 (3725 550);
DISPLAY INVISIBLE (3725 550);
FORCEPROP 1 LAST PATH I456
J 0
(3398 675);
DISPLAY 0.872340 (3398 675);
PAINT GREEN (3398 675);
DISPLAY INVISIBLE (3398 675);
FORCEADD TAP..1
(3400 625);
FORCEPROP 3 LASTPIN (3350 625) SIG_NAME P5E_CPU1_PE1_TX_DP<2>
J 0
(3360 635);
DISPLAY 0.659574 (3360 635);
PAINT MONO (3360 635);
DISPLAY INVISIBLE (3360 635);
FORCEPROP 1 LASTPIN (3350 625) BN 2
J 0
(3338 633);
DISPLAY 0.680851 (3338 633);
PAINT GREEN (3338 633);
FORCEPROP 2 LAST CDS_LIB standard
J 0
(3400 625);
PAINT MONO (3400 625);
DISPLAY INVISIBLE (3400 625);
FORCEPROP 1 LAST BODY_TYPE PLUMBING
J 0
(3400 675);
DISPLAY 0.872340 (3400 675);
PAINT GREEN (3400 675);
DISPLAY INVISIBLE (3400 675);
FORCEPROP 1 LAST HDL_TAP TRUE
J 0
(3725 500);
DISPLAY 0.872340 (3725 500);
DISPLAY INVISIBLE (3725 500);
FORCEPROP 1 LAST PATH I457
J 0
(3398 625);
DISPLAY 0.872340 (3398 625);
PAINT GREEN (3398 625);
DISPLAY INVISIBLE (3398 625);
FORCEADD TAP..1
(3400 825);
FORCEPROP 3 LASTPIN (3350 825) SIG_NAME P5E_CPU1_PE1_TX_DP<6>
J 0
(3360 835);
DISPLAY 0.659574 (3360 835);
PAINT MONO (3360 835);
DISPLAY INVISIBLE (3360 835);
FORCEPROP 1 LASTPIN (3350 825) BN 6
J 0
(3338 833);
DISPLAY 0.680851 (3338 833);
PAINT GREEN (3338 833);
FORCEPROP 2 LAST CDS_LIB standard
J 0
(3400 825);
PAINT MONO (3400 825);
DISPLAY INVISIBLE (3400 825);
FORCEPROP 1 LAST BODY_TYPE PLUMBING
J 0
(3400 875);
DISPLAY 0.872340 (3400 875);
PAINT GREEN (3400 875);
DISPLAY INVISIBLE (3400 875);
FORCEPROP 1 LAST HDL_TAP TRUE
J 0
(3725 700);
DISPLAY 0.872340 (3725 700);
DISPLAY INVISIBLE (3725 700);
FORCEPROP 1 LAST PATH I458
J 0
(3398 825);
DISPLAY 0.872340 (3398 825);
PAINT GREEN (3398 825);
DISPLAY INVISIBLE (3398 825);
FORCEADD TAP..1
(3400 775);
FORCEPROP 3 LASTPIN (3350 775) SIG_NAME P5E_CPU1_PE1_TX_DP<5>
J 0
(3360 785);
DISPLAY 0.659574 (3360 785);
PAINT MONO (3360 785);
DISPLAY INVISIBLE (3360 785);
FORCEPROP 1 LASTPIN (3350 775) BN 5
J 0
(3338 783);
DISPLAY 0.680851 (3338 783);
PAINT GREEN (3338 783);
FORCEPROP 2 LAST CDS_LIB standard
J 0
(3400 775);
PAINT MONO (3400 775);
DISPLAY INVISIBLE (3400 775);
FORCEPROP 1 LAST BODY_TYPE PLUMBING
J 0
(3400 825);
DISPLAY 0.872340 (3400 825);
PAINT GREEN (3400 825);
DISPLAY INVISIBLE (3400 825);
FORCEPROP 1 LAST HDL_TAP TRUE
J 0
(3725 650);
DISPLAY 0.872340 (3725 650);
DISPLAY INVISIBLE (3725 650);
FORCEPROP 1 LAST PATH I459
J 0
(3398 775);
DISPLAY 0.872340 (3398 775);
PAINT GREEN (3398 775);
DISPLAY INVISIBLE (3398 775);
FORCEADD TAP..1
(3400 725);
FORCEPROP 3 LASTPIN (3350 725) SIG_NAME P5E_CPU1_PE1_TX_DP<4>
J 0
(3360 735);
DISPLAY 0.659574 (3360 735);
PAINT MONO (3360 735);
DISPLAY INVISIBLE (3360 735);
FORCEPROP 1 LASTPIN (3350 725) BN 4
J 0
(3338 733);
DISPLAY 0.680851 (3338 733);
PAINT GREEN (3338 733);
FORCEPROP 2 LAST CDS_LIB standard
J 0
(3400 725);
PAINT MONO (3400 725);
DISPLAY INVISIBLE (3400 725);
FORCEPROP 1 LAST BODY_TYPE PLUMBING
J 0
(3400 775);
DISPLAY 0.872340 (3400 775);
PAINT GREEN (3400 775);
DISPLAY INVISIBLE (3400 775);
FORCEPROP 1 LAST HDL_TAP TRUE
J 0
(3725 600);
DISPLAY 0.872340 (3725 600);
DISPLAY INVISIBLE (3725 600);
FORCEPROP 1 LAST PATH I460
J 0
(3398 725);
DISPLAY 0.872340 (3398 725);
PAINT GREEN (3398 725);
DISPLAY INVISIBLE (3398 725);
FORCEADD TAP..1
(3400 875);
FORCEPROP 3 LASTPIN (3350 875) SIG_NAME P5E_CPU1_PE1_TX_DP<7>
J 0
(3360 885);
DISPLAY 0.659574 (3360 885);
PAINT MONO (3360 885);
DISPLAY INVISIBLE (3360 885);
FORCEPROP 1 LASTPIN (3350 875) BN 7
J 0
(3338 883);
DISPLAY 0.680851 (3338 883);
PAINT GREEN (3338 883);
FORCEPROP 2 LAST CDS_LIB standard
J 0
(3400 875);
PAINT MONO (3400 875);
DISPLAY INVISIBLE (3400 875);
FORCEPROP 1 LAST BODY_TYPE PLUMBING
J 0
(3400 925);
DISPLAY 0.872340 (3400 925);
PAINT GREEN (3400 925);
DISPLAY INVISIBLE (3400 925);
FORCEPROP 1 LAST HDL_TAP TRUE
J 0
(3725 750);
DISPLAY 0.872340 (3725 750);
DISPLAY INVISIBLE (3725 750);
FORCEPROP 1 LAST PATH I461
J 0
(3398 875);
DISPLAY 0.872340 (3398 875);
PAINT GREEN (3398 875);
DISPLAY INVISIBLE (3398 875);
FORCEADD TAP..1
(3400 925);
FORCEPROP 3 LASTPIN (3350 925) SIG_NAME P5E_CPU1_PE1_TX_DP<8>
J 0
(3360 935);
DISPLAY 0.659574 (3360 935);
PAINT MONO (3360 935);
DISPLAY INVISIBLE (3360 935);
FORCEPROP 1 LASTPIN (3350 925) BN 8
J 0
(3338 933);
DISPLAY 0.680851 (3338 933);
PAINT GREEN (3338 933);
FORCEPROP 2 LAST CDS_LIB standard
J 0
(3400 925);
PAINT MONO (3400 925);
DISPLAY INVISIBLE (3400 925);
FORCEPROP 1 LAST BODY_TYPE PLUMBING
J 0
(3400 975);
DISPLAY 0.872340 (3400 975);
PAINT GREEN (3400 975);
DISPLAY INVISIBLE (3400 975);
FORCEPROP 1 LAST HDL_TAP TRUE
J 0
(3725 800);
DISPLAY 0.872340 (3725 800);
DISPLAY INVISIBLE (3725 800);
FORCEPROP 1 LAST PATH I462
J 0
(3398 925);
DISPLAY 0.872340 (3398 925);
PAINT GREEN (3398 925);
DISPLAY INVISIBLE (3398 925);
FORCEADD TAP..1
(3400 1075);
FORCEPROP 3 LASTPIN (3350 1075) SIG_NAME P5E_CPU1_PE1_TX_DP<11>
J 0
(3360 1085);
DISPLAY 0.659574 (3360 1085);
PAINT MONO (3360 1085);
DISPLAY INVISIBLE (3360 1085);
FORCEPROP 1 LASTPIN (3350 1075) BN 11
J 0
(3338 1083);
DISPLAY 0.680851 (3338 1083);
PAINT GREEN (3338 1083);
FORCEPROP 2 LAST CDS_LIB standard
J 0
(3400 1075);
DISPLAY INVISIBLE (3400 1075);
FORCEPROP 1 LAST BODY_TYPE PLUMBING
J 0
(3400 1125);
DISPLAY 0.872340 (3400 1125);
PAINT GREEN (3400 1125);
DISPLAY INVISIBLE (3400 1125);
FORCEPROP 1 LAST HDL_TAP TRUE
J 0
(3725 950);
DISPLAY 0.872340 (3725 950);
DISPLAY INVISIBLE (3725 950);
FORCEPROP 1 LAST PATH I463
J 0
(3398 1075);
DISPLAY 0.872340 (3398 1075);
PAINT GREEN (3398 1075);
DISPLAY INVISIBLE (3398 1075);
FORCEADD TAP..1
(3400 1025);
FORCEPROP 3 LASTPIN (3350 1025) SIG_NAME P5E_CPU1_PE1_TX_DP<10>
J 0
(3360 1035);
DISPLAY 0.659574 (3360 1035);
PAINT MONO (3360 1035);
DISPLAY INVISIBLE (3360 1035);
FORCEPROP 1 LASTPIN (3350 1025) BN 10
J 0
(3338 1033);
DISPLAY 0.680851 (3338 1033);
PAINT GREEN (3338 1033);
FORCEPROP 2 LAST CDS_LIB standard
J 0
(3400 1025);
DISPLAY INVISIBLE (3400 1025);
FORCEPROP 1 LAST BODY_TYPE PLUMBING
J 0
(3400 1075);
DISPLAY 0.872340 (3400 1075);
PAINT GREEN (3400 1075);
DISPLAY INVISIBLE (3400 1075);
FORCEPROP 1 LAST HDL_TAP TRUE
J 0
(3725 900);
DISPLAY 0.872340 (3725 900);
DISPLAY INVISIBLE (3725 900);
FORCEPROP 1 LAST PATH I464
J 0
(3398 1025);
DISPLAY 0.872340 (3398 1025);
PAINT GREEN (3398 1025);
DISPLAY INVISIBLE (3398 1025);
FORCEADD TAP..1
(3400 975);
FORCEPROP 3 LASTPIN (3350 975) SIG_NAME P5E_CPU1_PE1_TX_DP<9>
J 0
(3360 985);
DISPLAY 0.659574 (3360 985);
PAINT MONO (3360 985);
DISPLAY INVISIBLE (3360 985);
FORCEPROP 1 LASTPIN (3350 975) BN 9
J 0
(3338 983);
DISPLAY 0.680851 (3338 983);
PAINT GREEN (3338 983);
FORCEPROP 2 LAST CDS_LIB standard
J 0
(3400 975);
DISPLAY INVISIBLE (3400 975);
FORCEPROP 1 LAST BODY_TYPE PLUMBING
J 0
(3400 1025);
DISPLAY 0.872340 (3400 1025);
PAINT GREEN (3400 1025);
DISPLAY INVISIBLE (3400 1025);
FORCEPROP 1 LAST HDL_TAP TRUE
J 0
(3725 850);
DISPLAY 0.872340 (3725 850);
DISPLAY INVISIBLE (3725 850);
FORCEPROP 1 LAST PATH I465
J 0
(3398 975);
DISPLAY 0.872340 (3398 975);
PAINT GREEN (3398 975);
DISPLAY INVISIBLE (3398 975);
FORCEADD TAP..1
(3400 1175);
FORCEPROP 3 LASTPIN (3350 1175) SIG_NAME P5E_CPU1_PE1_TX_DP<13>
J 0
(3360 1185);
DISPLAY 0.659574 (3360 1185);
PAINT MONO (3360 1185);
DISPLAY INVISIBLE (3360 1185);
FORCEPROP 1 LASTPIN (3350 1175) BN 13
J 0
(3338 1183);
DISPLAY 0.680851 (3338 1183);
PAINT GREEN (3338 1183);
FORCEPROP 2 LAST CDS_LIB standard
J 0
(3400 1175);
DISPLAY INVISIBLE (3400 1175);
FORCEPROP 1 LAST BODY_TYPE PLUMBING
J 0
(3400 1225);
DISPLAY 0.872340 (3400 1225);
PAINT GREEN (3400 1225);
DISPLAY INVISIBLE (3400 1225);
FORCEPROP 1 LAST HDL_TAP TRUE
J 0
(3725 1050);
DISPLAY 0.872340 (3725 1050);
DISPLAY INVISIBLE (3725 1050);
FORCEPROP 1 LAST PATH I466
J 0
(3398 1175);
DISPLAY 0.872340 (3398 1175);
PAINT GREEN (3398 1175);
DISPLAY INVISIBLE (3398 1175);
FORCEADD TAP..1
(3400 1125);
FORCEPROP 3 LASTPIN (3350 1125) SIG_NAME P5E_CPU1_PE1_TX_DP<12>
J 0
(3360 1135);
DISPLAY 0.659574 (3360 1135);
PAINT MONO (3360 1135);
DISPLAY INVISIBLE (3360 1135);
FORCEPROP 1 LASTPIN (3350 1125) BN 12
J 0
(3338 1133);
DISPLAY 0.680851 (3338 1133);
PAINT GREEN (3338 1133);
FORCEPROP 2 LAST CDS_LIB standard
J 0
(3400 1125);
DISPLAY INVISIBLE (3400 1125);
FORCEPROP 1 LAST BODY_TYPE PLUMBING
J 0
(3400 1175);
DISPLAY 0.872340 (3400 1175);
PAINT GREEN (3400 1175);
DISPLAY INVISIBLE (3400 1175);
FORCEPROP 1 LAST HDL_TAP TRUE
J 0
(3725 1000);
DISPLAY 0.872340 (3725 1000);
DISPLAY INVISIBLE (3725 1000);
FORCEPROP 1 LAST PATH I467
J 0
(3398 1125);
DISPLAY 0.872340 (3398 1125);
PAINT GREEN (3398 1125);
DISPLAY INVISIBLE (3398 1125);
FORCEADD TAP..1
(3400 1225);
FORCEPROP 3 LASTPIN (3350 1225) SIG_NAME P5E_CPU1_PE1_TX_DP<14>
J 0
(3360 1235);
DISPLAY 0.659574 (3360 1235);
PAINT MONO (3360 1235);
DISPLAY INVISIBLE (3360 1235);
FORCEPROP 1 LASTPIN (3350 1225) BN 14
J 0
(3338 1233);
DISPLAY 0.680851 (3338 1233);
PAINT GREEN (3338 1233);
FORCEPROP 2 LAST CDS_LIB standard
J 0
(3400 1225);
DISPLAY INVISIBLE (3400 1225);
FORCEPROP 1 LAST BODY_TYPE PLUMBING
J 0
(3400 1275);
DISPLAY 0.872340 (3400 1275);
PAINT GREEN (3400 1275);
DISPLAY INVISIBLE (3400 1275);
FORCEPROP 1 LAST HDL_TAP TRUE
J 0
(3725 1100);
DISPLAY 0.872340 (3725 1100);
DISPLAY INVISIBLE (3725 1100);
FORCEPROP 1 LAST PATH I468
J 0
(3398 1225);
DISPLAY 0.872340 (3398 1225);
PAINT GREEN (3398 1225);
DISPLAY INVISIBLE (3398 1225);
FORCEADD TAP..1
(3400 1275);
FORCEPROP 3 LASTPIN (3350 1275) SIG_NAME P5E_CPU1_PE1_TX_DP<15>
J 0
(3360 1285);
DISPLAY 0.659574 (3360 1285);
PAINT MONO (3360 1285);
DISPLAY INVISIBLE (3360 1285);
FORCEPROP 1 LASTPIN (3350 1275) BN 15
J 0
(3338 1283);
DISPLAY 0.680851 (3338 1283);
PAINT GREEN (3338 1283);
FORCEPROP 2 LAST CDS_LIB standard
J 0
(3400 1275);
DISPLAY INVISIBLE (3400 1275);
FORCEPROP 1 LAST BODY_TYPE PLUMBING
J 0
(3400 1325);
DISPLAY 0.872340 (3400 1325);
PAINT GREEN (3400 1325);
DISPLAY INVISIBLE (3400 1325);
FORCEPROP 1 LAST HDL_TAP TRUE
J 0
(3725 1150);
DISPLAY 0.872340 (3725 1150);
DISPLAY INVISIBLE (3725 1150);
FORCEPROP 1 LAST PATH I469
J 0
(3398 1275);
DISPLAY 0.872340 (3398 1275);
PAINT GREEN (3398 1275);
DISPLAY INVISIBLE (3398 1275);
FORCEADD OFFPAGE..2
(4500 450);
FORCEPROP 2 LAST $XR0 175 
J 0
(4689 450);
DISPLAY 0.638298 (4689 450);
PAINT MONO (4689 450);
FORCEPROP 2 LAST CDS_LIB standard
J 0
(4500 450);
PAINT MONO (4500 450);
DISPLAY INVISIBLE (4500 450);
FORCEPROP 1 LAST OFFPAGE TRUE
J 0
(4825 325);
DISPLAY 1.170213 (4825 325);
PAINT GREEN (4825 325);
DISPLAY INVISIBLE (4825 325);
FORCEPROP 1 LAST COMMENT_BODY TRUE
J 0
(4455 355);
DISPLAY 1.170213 (4455 355);
PAINT GREEN (4455 355);
DISPLAY INVISIBLE (4455 355);
FORCEPROP 2 LAST PATH I470
J 0
(4700 500);
DISPLAY 1.021277 (4700 500);
DISPLAY INVISIBLE (4700 500);
FORCEADD OFFPAGE..2
(4500 1300);
FORCEPROP 2 LAST $XR0 175 
J 0
(4689 1300);
DISPLAY 0.638298 (4689 1300);
PAINT MONO (4689 1300);
FORCEPROP 2 LAST CDS_LIB standard
J 0
(4500 1300);
PAINT MONO (4500 1300);
DISPLAY INVISIBLE (4500 1300);
FORCEPROP 1 LAST OFFPAGE TRUE
J 0
(4825 1175);
DISPLAY 1.170213 (4825 1175);
PAINT GREEN (4825 1175);
DISPLAY INVISIBLE (4825 1175);
FORCEPROP 1 LAST COMMENT_BODY TRUE
J 0
(4455 1205);
DISPLAY 1.170213 (4455 1205);
PAINT GREEN (4455 1205);
DISPLAY INVISIBLE (4455 1205);
FORCEPROP 2 LAST PATH I471
J 0
(4700 1350);
DISPLAY 1.021277 (4700 1350);
DISPLAY INVISIBLE (4700 1350);
FORCEADD TAP..1
(3400 -75);
FORCEPROP 3 LASTPIN (3350 -75) SIG_NAME P5E_CPU1_PE1_TX_DN<5>
J 0
(3360 -65);
DISPLAY 0.659574 (3360 -65);
PAINT MONO (3360 -65);
DISPLAY INVISIBLE (3360 -65);
FORCEPROP 1 LASTPIN (3350 -75) BN 5
J 0
(3338 -67);
DISPLAY 0.680851 (3338 -67);
PAINT GREEN (3338 -67);
FORCEPROP 2 LAST CDS_LIB standard
J 0
(3400 -75);
PAINT MONO (3400 -75);
DISPLAY INVISIBLE (3400 -75);
FORCEPROP 1 LAST BODY_TYPE PLUMBING
J 0
(3400 -25);
DISPLAY 0.872340 (3400 -25);
PAINT GREEN (3400 -25);
DISPLAY INVISIBLE (3400 -25);
FORCEPROP 1 LAST HDL_TAP TRUE
J 0
(3725 -200);
DISPLAY 0.872340 (3725 -200);
DISPLAY INVISIBLE (3725 -200);
FORCEPROP 1 LAST PATH I472
J 0
(3398 -75);
DISPLAY 0.872340 (3398 -75);
PAINT GREEN (3398 -75);
DISPLAY INVISIBLE (3398 -75);
FORCEADD TAP..1
(3400 -25);
FORCEPROP 3 LASTPIN (3350 -25) SIG_NAME P5E_CPU1_PE1_TX_DN<6>
J 0
(3360 -15);
DISPLAY 0.659574 (3360 -15);
PAINT MONO (3360 -15);
DISPLAY INVISIBLE (3360 -15);
FORCEPROP 1 LASTPIN (3350 -25) BN 6
J 0
(3338 -17);
DISPLAY 0.680851 (3338 -17);
PAINT GREEN (3338 -17);
FORCEPROP 2 LAST CDS_LIB standard
J 0
(3400 -25);
PAINT MONO (3400 -25);
DISPLAY INVISIBLE (3400 -25);
FORCEPROP 1 LAST BODY_TYPE PLUMBING
J 0
(3400 25);
DISPLAY 0.872340 (3400 25);
PAINT GREEN (3400 25);
DISPLAY INVISIBLE (3400 25);
FORCEPROP 1 LAST HDL_TAP TRUE
J 0
(3725 -150);
DISPLAY 0.872340 (3725 -150);
DISPLAY INVISIBLE (3725 -150);
FORCEPROP 1 LAST PATH I473
J 0
(3398 -25);
DISPLAY 0.872340 (3398 -25);
PAINT GREEN (3398 -25);
DISPLAY INVISIBLE (3398 -25);
FORCEADD OFFPAGE..2
(4500 4075);
FORCEPROP 2 LAST $XR0 176 
J 0
(4689 4075);
DISPLAY 0.638298 (4689 4075);
PAINT MONO (4689 4075);
FORCEPROP 2 LAST CDS_LIB standard
J 0
(4500 4075);
PAINT MONO (4500 4075);
DISPLAY INVISIBLE (4500 4075);
FORCEPROP 1 LAST OFFPAGE TRUE
J 0
(4825 3950);
DISPLAY 1.170213 (4825 3950);
PAINT GREEN (4825 3950);
DISPLAY INVISIBLE (4825 3950);
FORCEPROP 1 LAST COMMENT_BODY TRUE
J 0
(4455 3980);
DISPLAY 1.170213 (4455 3980);
PAINT GREEN (4455 3980);
DISPLAY INVISIBLE (4455 3980);
FORCEPROP 2 LAST PATH I474
J 0
(4700 4125);
DISPLAY 1.021277 (4700 4125);
DISPLAY INVISIBLE (4700 4125);
FORCEADD OFFPAGE..2
(4500 3225);
FORCEPROP 2 LAST $XR0 176 
J 0
(4689 3225);
DISPLAY 0.638298 (4689 3225);
PAINT MONO (4689 3225);
FORCEPROP 2 LAST CDS_LIB standard
J 0
(4500 3225);
PAINT MONO (4500 3225);
DISPLAY INVISIBLE (4500 3225);
FORCEPROP 1 LAST OFFPAGE TRUE
J 0
(4825 3100);
DISPLAY 1.170213 (4825 3100);
PAINT GREEN (4825 3100);
DISPLAY INVISIBLE (4825 3100);
FORCEPROP 1 LAST COMMENT_BODY TRUE
J 0
(4455 3130);
DISPLAY 1.170213 (4455 3130);
PAINT GREEN (4455 3130);
DISPLAY INVISIBLE (4455 3130);
FORCEPROP 2 LAST PATH I475
J 0
(4700 3275);
DISPLAY 1.021277 (4700 3275);
DISPLAY INVISIBLE (4700 3275);
FORCEADD TAP..1
(3400 3950);
FORCEPROP 3 LASTPIN (3350 3950) SIG_NAME P5E_CPU1_PE0_TX_DP<13>
J 0
(3360 3960);
DISPLAY 0.659574 (3360 3960);
PAINT MONO (3360 3960);
DISPLAY INVISIBLE (3360 3960);
FORCEPROP 1 LASTPIN (3350 3950) BN 13
J 0
(3338 3958);
DISPLAY 0.680851 (3338 3958);
PAINT GREEN (3338 3958);
FORCEPROP 2 LAST CDS_LIB standard
J 0
(3400 3950);
DISPLAY INVISIBLE (3400 3950);
FORCEPROP 1 LAST BODY_TYPE PLUMBING
J 0
(3400 4000);
DISPLAY 0.872340 (3400 4000);
PAINT GREEN (3400 4000);
DISPLAY INVISIBLE (3400 4000);
FORCEPROP 1 LAST HDL_TAP TRUE
J 0
(3725 3825);
DISPLAY 0.872340 (3725 3825);
DISPLAY INVISIBLE (3725 3825);
FORCEPROP 1 LAST PATH I476
J 0
(3398 3950);
DISPLAY 0.872340 (3398 3950);
PAINT GREEN (3398 3950);
DISPLAY INVISIBLE (3398 3950);
FORCEADD TAP..1
(3400 4050);
FORCEPROP 3 LASTPIN (3350 4050) SIG_NAME P5E_CPU1_PE0_TX_DP<15>
J 0
(3360 4060);
DISPLAY 0.659574 (3360 4060);
PAINT MONO (3360 4060);
DISPLAY INVISIBLE (3360 4060);
FORCEPROP 1 LASTPIN (3350 4050) BN 15
J 0
(3338 4058);
DISPLAY 0.680851 (3338 4058);
PAINT GREEN (3338 4058);
FORCEPROP 2 LAST CDS_LIB standard
J 0
(3400 4050);
DISPLAY INVISIBLE (3400 4050);
FORCEPROP 1 LAST BODY_TYPE PLUMBING
J 0
(3400 4100);
DISPLAY 0.872340 (3400 4100);
PAINT GREEN (3400 4100);
DISPLAY INVISIBLE (3400 4100);
FORCEPROP 1 LAST HDL_TAP TRUE
J 0
(3725 3925);
DISPLAY 0.872340 (3725 3925);
DISPLAY INVISIBLE (3725 3925);
FORCEPROP 1 LAST PATH I477
J 0
(3398 4050);
DISPLAY 0.872340 (3398 4050);
PAINT GREEN (3398 4050);
DISPLAY INVISIBLE (3398 4050);
FORCEADD TAP..1
(3400 4000);
FORCEPROP 3 LASTPIN (3350 4000) SIG_NAME P5E_CPU1_PE0_TX_DP<14>
J 0
(3360 4010);
DISPLAY 0.659574 (3360 4010);
PAINT MONO (3360 4010);
DISPLAY INVISIBLE (3360 4010);
FORCEPROP 1 LASTPIN (3350 4000) BN 14
J 0
(3338 4008);
DISPLAY 0.680851 (3338 4008);
PAINT GREEN (3338 4008);
FORCEPROP 2 LAST CDS_LIB standard
J 0
(3400 4000);
DISPLAY INVISIBLE (3400 4000);
FORCEPROP 1 LAST BODY_TYPE PLUMBING
J 0
(3400 4050);
DISPLAY 0.872340 (3400 4050);
PAINT GREEN (3400 4050);
DISPLAY INVISIBLE (3400 4050);
FORCEPROP 1 LAST HDL_TAP TRUE
J 0
(3725 3875);
DISPLAY 0.872340 (3725 3875);
DISPLAY INVISIBLE (3725 3875);
FORCEPROP 1 LAST PATH I478
J 0
(3398 4000);
DISPLAY 0.872340 (3398 4000);
PAINT GREEN (3398 4000);
DISPLAY INVISIBLE (3398 4000);
FORCEADD TAP..1
(3400 3800);
FORCEPROP 3 LASTPIN (3350 3800) SIG_NAME P5E_CPU1_PE0_TX_DP<10>
J 0
(3360 3810);
DISPLAY 0.659574 (3360 3810);
PAINT MONO (3360 3810);
DISPLAY INVISIBLE (3360 3810);
FORCEPROP 1 LASTPIN (3350 3800) BN 10
J 0
(3338 3808);
DISPLAY 0.680851 (3338 3808);
PAINT GREEN (3338 3808);
FORCEPROP 2 LAST CDS_LIB standard
J 0
(3400 3800);
DISPLAY INVISIBLE (3400 3800);
FORCEPROP 1 LAST BODY_TYPE PLUMBING
J 0
(3400 3850);
DISPLAY 0.872340 (3400 3850);
PAINT GREEN (3400 3850);
DISPLAY INVISIBLE (3400 3850);
FORCEPROP 1 LAST HDL_TAP TRUE
J 0
(3725 3675);
DISPLAY 0.872340 (3725 3675);
DISPLAY INVISIBLE (3725 3675);
FORCEPROP 1 LAST PATH I479
J 0
(3398 3800);
DISPLAY 0.872340 (3398 3800);
PAINT GREEN (3398 3800);
DISPLAY INVISIBLE (3398 3800);
FORCEADD TAP..1
(3400 3900);
FORCEPROP 3 LASTPIN (3350 3900) SIG_NAME P5E_CPU1_PE0_TX_DP<12>
J 0
(3360 3910);
DISPLAY 0.659574 (3360 3910);
PAINT MONO (3360 3910);
DISPLAY INVISIBLE (3360 3910);
FORCEPROP 1 LASTPIN (3350 3900) BN 12
J 0
(3338 3908);
DISPLAY 0.680851 (3338 3908);
PAINT GREEN (3338 3908);
FORCEPROP 2 LAST CDS_LIB standard
J 0
(3400 3900);
DISPLAY INVISIBLE (3400 3900);
FORCEPROP 1 LAST BODY_TYPE PLUMBING
J 0
(3400 3950);
DISPLAY 0.872340 (3400 3950);
PAINT GREEN (3400 3950);
DISPLAY INVISIBLE (3400 3950);
FORCEPROP 1 LAST HDL_TAP TRUE
J 0
(3725 3775);
DISPLAY 0.872340 (3725 3775);
DISPLAY INVISIBLE (3725 3775);
FORCEPROP 1 LAST PATH I480
J 0
(3398 3900);
DISPLAY 0.872340 (3398 3900);
PAINT GREEN (3398 3900);
DISPLAY INVISIBLE (3398 3900);
FORCEADD TAP..1
(3400 3850);
FORCEPROP 3 LASTPIN (3350 3850) SIG_NAME P5E_CPU1_PE0_TX_DP<11>
J 0
(3360 3860);
DISPLAY 0.659574 (3360 3860);
PAINT MONO (3360 3860);
DISPLAY INVISIBLE (3360 3860);
FORCEPROP 1 LASTPIN (3350 3850) BN 11
J 0
(3338 3858);
DISPLAY 0.680851 (3338 3858);
PAINT GREEN (3338 3858);
FORCEPROP 2 LAST CDS_LIB standard
J 0
(3400 3850);
DISPLAY INVISIBLE (3400 3850);
FORCEPROP 1 LAST BODY_TYPE PLUMBING
J 0
(3400 3900);
DISPLAY 0.872340 (3400 3900);
PAINT GREEN (3400 3900);
DISPLAY INVISIBLE (3400 3900);
FORCEPROP 1 LAST HDL_TAP TRUE
J 0
(3725 3725);
DISPLAY 0.872340 (3725 3725);
DISPLAY INVISIBLE (3725 3725);
FORCEPROP 1 LAST PATH I481
J 0
(3398 3850);
DISPLAY 0.872340 (3398 3850);
PAINT GREEN (3398 3850);
DISPLAY INVISIBLE (3398 3850);
FORCEADD TAP..1
(3400 3750);
FORCEPROP 3 LASTPIN (3350 3750) SIG_NAME P5E_CPU1_PE0_TX_DP<9>
J 0
(3360 3760);
DISPLAY 0.659574 (3360 3760);
PAINT MONO (3360 3760);
DISPLAY INVISIBLE (3360 3760);
FORCEPROP 1 LASTPIN (3350 3750) BN 9
J 0
(3338 3758);
DISPLAY 0.680851 (3338 3758);
PAINT GREEN (3338 3758);
FORCEPROP 2 LAST CDS_LIB standard
J 0
(3400 3750);
DISPLAY INVISIBLE (3400 3750);
FORCEPROP 1 LAST BODY_TYPE PLUMBING
J 0
(3400 3800);
DISPLAY 0.872340 (3400 3800);
PAINT GREEN (3400 3800);
DISPLAY INVISIBLE (3400 3800);
FORCEPROP 1 LAST HDL_TAP TRUE
J 0
(3725 3625);
DISPLAY 0.872340 (3725 3625);
DISPLAY INVISIBLE (3725 3625);
FORCEPROP 1 LAST PATH I482
J 0
(3398 3750);
DISPLAY 0.872340 (3398 3750);
PAINT GREEN (3398 3750);
DISPLAY INVISIBLE (3398 3750);
FORCEADD TAP..1
(3400 3700);
FORCEPROP 3 LASTPIN (3350 3700) SIG_NAME P5E_CPU1_PE0_TX_DP<8>
J 0
(3360 3710);
DISPLAY 0.659574 (3360 3710);
PAINT MONO (3360 3710);
DISPLAY INVISIBLE (3360 3710);
FORCEPROP 1 LASTPIN (3350 3700) BN 8
J 0
(3338 3708);
DISPLAY 0.680851 (3338 3708);
PAINT GREEN (3338 3708);
FORCEPROP 2 LAST CDS_LIB standard
J 0
(3400 3700);
PAINT MONO (3400 3700);
DISPLAY INVISIBLE (3400 3700);
FORCEPROP 1 LAST BODY_TYPE PLUMBING
J 0
(3400 3750);
DISPLAY 0.872340 (3400 3750);
PAINT GREEN (3400 3750);
DISPLAY INVISIBLE (3400 3750);
FORCEPROP 1 LAST HDL_TAP TRUE
J 0
(3725 3575);
DISPLAY 0.872340 (3725 3575);
DISPLAY INVISIBLE (3725 3575);
FORCEPROP 1 LAST PATH I483
J 0
(3398 3700);
DISPLAY 0.872340 (3398 3700);
PAINT GREEN (3398 3700);
DISPLAY INVISIBLE (3398 3700);
FORCEADD TAP..1
(3400 3600);
FORCEPROP 3 LASTPIN (3350 3600) SIG_NAME P5E_CPU1_PE0_TX_DP<6>
J 0
(3360 3610);
DISPLAY 0.659574 (3360 3610);
PAINT MONO (3360 3610);
DISPLAY INVISIBLE (3360 3610);
FORCEPROP 1 LASTPIN (3350 3600) BN 6
J 0
(3338 3608);
DISPLAY 0.680851 (3338 3608);
PAINT GREEN (3338 3608);
FORCEPROP 2 LAST CDS_LIB standard
J 0
(3400 3600);
PAINT MONO (3400 3600);
DISPLAY INVISIBLE (3400 3600);
FORCEPROP 1 LAST BODY_TYPE PLUMBING
J 0
(3400 3650);
DISPLAY 0.872340 (3400 3650);
PAINT GREEN (3400 3650);
DISPLAY INVISIBLE (3400 3650);
FORCEPROP 1 LAST HDL_TAP TRUE
J 0
(3725 3475);
DISPLAY 0.872340 (3725 3475);
DISPLAY INVISIBLE (3725 3475);
FORCEPROP 1 LAST PATH I484
J 0
(3398 3600);
DISPLAY 0.872340 (3398 3600);
PAINT GREEN (3398 3600);
DISPLAY INVISIBLE (3398 3600);
FORCEADD TAP..1
(3400 3550);
FORCEPROP 3 LASTPIN (3350 3550) SIG_NAME P5E_CPU1_PE0_TX_DP<5>
J 0
(3360 3560);
DISPLAY 0.659574 (3360 3560);
PAINT MONO (3360 3560);
DISPLAY INVISIBLE (3360 3560);
FORCEPROP 1 LASTPIN (3350 3550) BN 5
J 0
(3338 3558);
DISPLAY 0.680851 (3338 3558);
PAINT GREEN (3338 3558);
FORCEPROP 2 LAST CDS_LIB standard
J 0
(3400 3550);
PAINT MONO (3400 3550);
DISPLAY INVISIBLE (3400 3550);
FORCEPROP 1 LAST BODY_TYPE PLUMBING
J 0
(3400 3600);
DISPLAY 0.872340 (3400 3600);
PAINT GREEN (3400 3600);
DISPLAY INVISIBLE (3400 3600);
FORCEPROP 1 LAST HDL_TAP TRUE
J 0
(3725 3425);
DISPLAY 0.872340 (3725 3425);
DISPLAY INVISIBLE (3725 3425);
FORCEPROP 1 LAST PATH I485
J 0
(3398 3550);
DISPLAY 0.872340 (3398 3550);
PAINT GREEN (3398 3550);
DISPLAY INVISIBLE (3398 3550);
FORCEADD TAP..1
(3400 3650);
FORCEPROP 3 LASTPIN (3350 3650) SIG_NAME P5E_CPU1_PE0_TX_DP<7>
J 0
(3360 3660);
DISPLAY 0.659574 (3360 3660);
PAINT MONO (3360 3660);
DISPLAY INVISIBLE (3360 3660);
FORCEPROP 1 LASTPIN (3350 3650) BN 7
J 0
(3338 3658);
DISPLAY 0.680851 (3338 3658);
PAINT GREEN (3338 3658);
FORCEPROP 2 LAST CDS_LIB standard
J 0
(3400 3650);
PAINT MONO (3400 3650);
DISPLAY INVISIBLE (3400 3650);
FORCEPROP 1 LAST BODY_TYPE PLUMBING
J 0
(3400 3700);
DISPLAY 0.872340 (3400 3700);
PAINT GREEN (3400 3700);
DISPLAY INVISIBLE (3400 3700);
FORCEPROP 1 LAST HDL_TAP TRUE
J 0
(3725 3525);
DISPLAY 0.872340 (3725 3525);
DISPLAY INVISIBLE (3725 3525);
FORCEPROP 1 LAST PATH I486
J 0
(3398 3650);
DISPLAY 0.872340 (3398 3650);
PAINT GREEN (3398 3650);
DISPLAY INVISIBLE (3398 3650);
FORCEADD TAP..1
(3400 3500);
FORCEPROP 3 LASTPIN (3350 3500) SIG_NAME P5E_CPU1_PE0_TX_DP<4>
J 0
(3360 3510);
DISPLAY 0.659574 (3360 3510);
PAINT MONO (3360 3510);
DISPLAY INVISIBLE (3360 3510);
FORCEPROP 1 LASTPIN (3350 3500) BN 4
J 0
(3338 3508);
DISPLAY 0.680851 (3338 3508);
PAINT GREEN (3338 3508);
FORCEPROP 2 LAST CDS_LIB standard
J 0
(3400 3500);
PAINT MONO (3400 3500);
DISPLAY INVISIBLE (3400 3500);
FORCEPROP 1 LAST BODY_TYPE PLUMBING
J 0
(3400 3550);
DISPLAY 0.872340 (3400 3550);
PAINT GREEN (3400 3550);
DISPLAY INVISIBLE (3400 3550);
FORCEPROP 1 LAST HDL_TAP TRUE
J 0
(3725 3375);
DISPLAY 0.872340 (3725 3375);
DISPLAY INVISIBLE (3725 3375);
FORCEPROP 1 LAST PATH I487
J 0
(3398 3500);
DISPLAY 0.872340 (3398 3500);
PAINT GREEN (3398 3500);
DISPLAY INVISIBLE (3398 3500);
FORCEADD TAP..1
(3400 3450);
FORCEPROP 3 LASTPIN (3350 3450) SIG_NAME P5E_CPU1_PE0_TX_DP<3>
J 0
(3360 3460);
DISPLAY 0.659574 (3360 3460);
PAINT MONO (3360 3460);
DISPLAY INVISIBLE (3360 3460);
FORCEPROP 1 LASTPIN (3350 3450) BN 3
J 0
(3338 3458);
DISPLAY 0.680851 (3338 3458);
PAINT GREEN (3338 3458);
FORCEPROP 2 LAST CDS_LIB standard
J 0
(3400 3450);
PAINT MONO (3400 3450);
DISPLAY INVISIBLE (3400 3450);
FORCEPROP 1 LAST BODY_TYPE PLUMBING
J 0
(3400 3500);
DISPLAY 0.872340 (3400 3500);
PAINT GREEN (3400 3500);
DISPLAY INVISIBLE (3400 3500);
FORCEPROP 1 LAST HDL_TAP TRUE
J 0
(3725 3325);
DISPLAY 0.872340 (3725 3325);
DISPLAY INVISIBLE (3725 3325);
FORCEPROP 1 LAST PATH I488
J 0
(3398 3450);
DISPLAY 0.872340 (3398 3450);
PAINT GREEN (3398 3450);
DISPLAY INVISIBLE (3398 3450);
FORCEADD TAP..1
(3400 3300);
FORCEPROP 3 LASTPIN (3350 3300) SIG_NAME P5E_CPU1_PE0_TX_DP<0>
J 0
(3360 3310);
DISPLAY 0.659574 (3360 3310);
PAINT MONO (3360 3310);
DISPLAY INVISIBLE (3360 3310);
FORCEPROP 1 LASTPIN (3350 3300) BN 0
J 0
(3338 3308);
DISPLAY 0.680851 (3338 3308);
PAINT GREEN (3338 3308);
FORCEPROP 2 LAST CDS_LIB standard
J 0
(3400 3300);
PAINT MONO (3400 3300);
DISPLAY INVISIBLE (3400 3300);
FORCEPROP 1 LAST BODY_TYPE PLUMBING
J 0
(3400 3350);
DISPLAY 0.872340 (3400 3350);
PAINT GREEN (3400 3350);
DISPLAY INVISIBLE (3400 3350);
FORCEPROP 1 LAST HDL_TAP TRUE
J 0
(3725 3175);
DISPLAY 0.872340 (3725 3175);
DISPLAY INVISIBLE (3725 3175);
FORCEPROP 1 LAST PATH I489
J 0
(3398 3300);
DISPLAY 0.872340 (3398 3300);
PAINT GREEN (3398 3300);
DISPLAY INVISIBLE (3398 3300);
FORCEADD TAP..1
(3400 3350);
FORCEPROP 3 LASTPIN (3350 3350) SIG_NAME P5E_CPU1_PE0_TX_DP<1>
J 0
(3360 3360);
DISPLAY 0.659574 (3360 3360);
PAINT MONO (3360 3360);
DISPLAY INVISIBLE (3360 3360);
FORCEPROP 1 LASTPIN (3350 3350) BN 1
J 0
(3338 3358);
DISPLAY 0.680851 (3338 3358);
PAINT GREEN (3338 3358);
FORCEPROP 2 LAST CDS_LIB standard
J 0
(3400 3350);
PAINT MONO (3400 3350);
DISPLAY INVISIBLE (3400 3350);
FORCEPROP 1 LAST BODY_TYPE PLUMBING
J 0
(3400 3400);
DISPLAY 0.872340 (3400 3400);
PAINT GREEN (3400 3400);
DISPLAY INVISIBLE (3400 3400);
FORCEPROP 1 LAST HDL_TAP TRUE
J 0
(3725 3225);
DISPLAY 0.872340 (3725 3225);
DISPLAY INVISIBLE (3725 3225);
FORCEPROP 1 LAST PATH I490
J 0
(3398 3350);
DISPLAY 0.872340 (3398 3350);
PAINT GREEN (3398 3350);
DISPLAY INVISIBLE (3398 3350);
FORCEADD TAP..1
(3400 3400);
FORCEPROP 3 LASTPIN (3350 3400) SIG_NAME P5E_CPU1_PE0_TX_DP<2>
J 0
(3360 3410);
DISPLAY 0.659574 (3360 3410);
PAINT MONO (3360 3410);
DISPLAY INVISIBLE (3360 3410);
FORCEPROP 1 LASTPIN (3350 3400) BN 2
J 0
(3338 3408);
DISPLAY 0.680851 (3338 3408);
PAINT GREEN (3338 3408);
FORCEPROP 2 LAST CDS_LIB standard
J 0
(3400 3400);
PAINT MONO (3400 3400);
DISPLAY INVISIBLE (3400 3400);
FORCEPROP 1 LAST BODY_TYPE PLUMBING
J 0
(3400 3450);
DISPLAY 0.872340 (3400 3450);
PAINT GREEN (3400 3450);
DISPLAY INVISIBLE (3400 3450);
FORCEPROP 1 LAST HDL_TAP TRUE
J 0
(3725 3275);
DISPLAY 0.872340 (3725 3275);
DISPLAY INVISIBLE (3725 3275);
FORCEPROP 1 LAST PATH I491
J 0
(3398 3400);
DISPLAY 0.872340 (3398 3400);
PAINT GREEN (3398 3400);
DISPLAY INVISIBLE (3398 3400);
FORCEADD TAP..1
(3400 3200);
FORCEPROP 3 LASTPIN (3350 3200) SIG_NAME P5E_CPU1_PE0_TX_DN<15>
J 0
(3360 3210);
DISPLAY 0.659574 (3360 3210);
PAINT MONO (3360 3210);
DISPLAY INVISIBLE (3360 3210);
FORCEPROP 1 LASTPIN (3350 3200) BN 15
J 0
(3338 3208);
DISPLAY 0.680851 (3338 3208);
PAINT GREEN (3338 3208);
FORCEPROP 2 LAST CDS_LIB standard
J 0
(3400 3200);
DISPLAY INVISIBLE (3400 3200);
FORCEPROP 1 LAST BODY_TYPE PLUMBING
J 0
(3400 3250);
DISPLAY 0.872340 (3400 3250);
PAINT GREEN (3400 3250);
DISPLAY INVISIBLE (3400 3250);
FORCEPROP 1 LAST HDL_TAP TRUE
J 0
(3725 3075);
DISPLAY 0.872340 (3725 3075);
DISPLAY INVISIBLE (3725 3075);
FORCEPROP 1 LAST PATH I492
J 0
(3398 3200);
DISPLAY 0.872340 (3398 3200);
PAINT GREEN (3398 3200);
DISPLAY INVISIBLE (3398 3200);
FORCEADD TAP..1
(3400 3050);
FORCEPROP 3 LASTPIN (3350 3050) SIG_NAME P5E_CPU1_PE0_TX_DN<12>
J 0
(3360 3060);
DISPLAY 0.659574 (3360 3060);
PAINT MONO (3360 3060);
DISPLAY INVISIBLE (3360 3060);
FORCEPROP 1 LASTPIN (3350 3050) BN 12
J 0
(3338 3058);
DISPLAY 0.680851 (3338 3058);
PAINT GREEN (3338 3058);
FORCEPROP 2 LAST CDS_LIB standard
J 0
(3400 3050);
DISPLAY INVISIBLE (3400 3050);
FORCEPROP 1 LAST BODY_TYPE PLUMBING
J 0
(3400 3100);
DISPLAY 0.872340 (3400 3100);
PAINT GREEN (3400 3100);
DISPLAY INVISIBLE (3400 3100);
FORCEPROP 1 LAST HDL_TAP TRUE
J 0
(3725 2925);
DISPLAY 0.872340 (3725 2925);
DISPLAY INVISIBLE (3725 2925);
FORCEPROP 1 LAST PATH I493
J 0
(3398 3050);
DISPLAY 0.872340 (3398 3050);
PAINT GREEN (3398 3050);
DISPLAY INVISIBLE (3398 3050);
FORCEADD TAP..1
(3400 3100);
FORCEPROP 3 LASTPIN (3350 3100) SIG_NAME P5E_CPU1_PE0_TX_DN<13>
J 0
(3360 3110);
DISPLAY 0.659574 (3360 3110);
PAINT MONO (3360 3110);
DISPLAY INVISIBLE (3360 3110);
FORCEPROP 1 LASTPIN (3350 3100) BN 13
J 0
(3338 3108);
DISPLAY 0.680851 (3338 3108);
PAINT GREEN (3338 3108);
FORCEPROP 2 LAST CDS_LIB standard
J 0
(3400 3100);
DISPLAY INVISIBLE (3400 3100);
FORCEPROP 1 LAST BODY_TYPE PLUMBING
J 0
(3400 3150);
DISPLAY 0.872340 (3400 3150);
PAINT GREEN (3400 3150);
DISPLAY INVISIBLE (3400 3150);
FORCEPROP 1 LAST HDL_TAP TRUE
J 0
(3725 2975);
DISPLAY 0.872340 (3725 2975);
DISPLAY INVISIBLE (3725 2975);
FORCEPROP 1 LAST PATH I494
J 0
(3398 3100);
DISPLAY 0.872340 (3398 3100);
PAINT GREEN (3398 3100);
DISPLAY INVISIBLE (3398 3100);
FORCEADD TAP..1
(3400 3150);
FORCEPROP 3 LASTPIN (3350 3150) SIG_NAME P5E_CPU1_PE0_TX_DN<14>
J 0
(3360 3160);
DISPLAY 0.659574 (3360 3160);
PAINT MONO (3360 3160);
DISPLAY INVISIBLE (3360 3160);
FORCEPROP 1 LASTPIN (3350 3150) BN 14
J 0
(3338 3158);
DISPLAY 0.680851 (3338 3158);
PAINT GREEN (3338 3158);
FORCEPROP 2 LAST CDS_LIB standard
J 0
(3400 3150);
DISPLAY INVISIBLE (3400 3150);
FORCEPROP 1 LAST BODY_TYPE PLUMBING
J 0
(3400 3200);
DISPLAY 0.872340 (3400 3200);
PAINT GREEN (3400 3200);
DISPLAY INVISIBLE (3400 3200);
FORCEPROP 1 LAST HDL_TAP TRUE
J 0
(3725 3025);
DISPLAY 0.872340 (3725 3025);
DISPLAY INVISIBLE (3725 3025);
FORCEPROP 1 LAST PATH I495
J 0
(3398 3150);
DISPLAY 0.872340 (3398 3150);
PAINT GREEN (3398 3150);
DISPLAY INVISIBLE (3398 3150);
FORCEADD TAP..1
(3400 2950);
FORCEPROP 3 LASTPIN (3350 2950) SIG_NAME P5E_CPU1_PE0_TX_DN<10>
J 0
(3360 2960);
DISPLAY 0.659574 (3360 2960);
PAINT MONO (3360 2960);
DISPLAY INVISIBLE (3360 2960);
FORCEPROP 1 LASTPIN (3350 2950) BN 10
J 0
(3338 2958);
DISPLAY 0.680851 (3338 2958);
PAINT GREEN (3338 2958);
FORCEPROP 2 LAST CDS_LIB standard
J 0
(3400 2950);
DISPLAY INVISIBLE (3400 2950);
FORCEPROP 1 LAST BODY_TYPE PLUMBING
J 0
(3400 3000);
DISPLAY 0.872340 (3400 3000);
PAINT GREEN (3400 3000);
DISPLAY INVISIBLE (3400 3000);
FORCEPROP 1 LAST HDL_TAP TRUE
J 0
(3725 2825);
DISPLAY 0.872340 (3725 2825);
DISPLAY INVISIBLE (3725 2825);
FORCEPROP 1 LAST PATH I496
J 0
(3398 2950);
DISPLAY 0.872340 (3398 2950);
PAINT GREEN (3398 2950);
DISPLAY INVISIBLE (3398 2950);
FORCEADD TAP..1
(3400 3000);
FORCEPROP 3 LASTPIN (3350 3000) SIG_NAME P5E_CPU1_PE0_TX_DN<11>
J 0
(3360 3010);
DISPLAY 0.659574 (3360 3010);
PAINT MONO (3360 3010);
DISPLAY INVISIBLE (3360 3010);
FORCEPROP 1 LASTPIN (3350 3000) BN 11
J 0
(3338 3008);
DISPLAY 0.680851 (3338 3008);
PAINT GREEN (3338 3008);
FORCEPROP 2 LAST CDS_LIB standard
J 0
(3400 3000);
DISPLAY INVISIBLE (3400 3000);
FORCEPROP 1 LAST BODY_TYPE PLUMBING
J 0
(3400 3050);
DISPLAY 0.872340 (3400 3050);
PAINT GREEN (3400 3050);
DISPLAY INVISIBLE (3400 3050);
FORCEPROP 1 LAST HDL_TAP TRUE
J 0
(3725 2875);
DISPLAY 0.872340 (3725 2875);
DISPLAY INVISIBLE (3725 2875);
FORCEPROP 1 LAST PATH I497
J 0
(3398 3000);
DISPLAY 0.872340 (3398 3000);
PAINT GREEN (3398 3000);
DISPLAY INVISIBLE (3398 3000);
FORCEADD TAP..1
(3400 2800);
FORCEPROP 3 LASTPIN (3350 2800) SIG_NAME P5E_CPU1_PE0_TX_DN<7>
J 0
(3360 2810);
DISPLAY 0.659574 (3360 2810);
PAINT MONO (3360 2810);
DISPLAY INVISIBLE (3360 2810);
FORCEPROP 1 LASTPIN (3350 2800) BN 7
J 0
(3338 2808);
DISPLAY 0.680851 (3338 2808);
PAINT GREEN (3338 2808);
FORCEPROP 2 LAST CDS_LIB standard
J 0
(3400 2800);
PAINT MONO (3400 2800);
DISPLAY INVISIBLE (3400 2800);
FORCEPROP 1 LAST BODY_TYPE PLUMBING
J 0
(3400 2850);
DISPLAY 0.872340 (3400 2850);
PAINT GREEN (3400 2850);
DISPLAY INVISIBLE (3400 2850);
FORCEPROP 1 LAST HDL_TAP TRUE
J 0
(3725 2675);
DISPLAY 0.872340 (3725 2675);
DISPLAY INVISIBLE (3725 2675);
FORCEPROP 1 LAST PATH I498
J 0
(3398 2800);
DISPLAY 0.872340 (3398 2800);
PAINT GREEN (3398 2800);
DISPLAY INVISIBLE (3398 2800);
FORCEADD TAP..1
(3400 2850);
FORCEPROP 3 LASTPIN (3350 2850) SIG_NAME P5E_CPU1_PE0_TX_DN<8>
J 0
(3360 2860);
DISPLAY 0.659574 (3360 2860);
PAINT MONO (3360 2860);
DISPLAY INVISIBLE (3360 2860);
FORCEPROP 1 LASTPIN (3350 2850) BN 8
J 0
(3338 2858);
DISPLAY 0.680851 (3338 2858);
PAINT GREEN (3338 2858);
FORCEPROP 2 LAST CDS_LIB standard
J 0
(3400 2850);
PAINT MONO (3400 2850);
DISPLAY INVISIBLE (3400 2850);
FORCEPROP 1 LAST BODY_TYPE PLUMBING
J 0
(3400 2900);
DISPLAY 0.872340 (3400 2900);
PAINT GREEN (3400 2900);
DISPLAY INVISIBLE (3400 2900);
FORCEPROP 1 LAST HDL_TAP TRUE
J 0
(3725 2725);
DISPLAY 0.872340 (3725 2725);
DISPLAY INVISIBLE (3725 2725);
FORCEPROP 1 LAST PATH I499
J 0
(3398 2850);
DISPLAY 0.872340 (3398 2850);
PAINT GREEN (3398 2850);
DISPLAY INVISIBLE (3398 2850);
FORCEADD TAP..1
(3400 2900);
FORCEPROP 3 LASTPIN (3350 2900) SIG_NAME P5E_CPU1_PE0_TX_DN<9>
J 0
(3360 2910);
DISPLAY 0.659574 (3360 2910);
PAINT MONO (3360 2910);
DISPLAY INVISIBLE (3360 2910);
FORCEPROP 1 LASTPIN (3350 2900) BN 9
J 0
(3338 2908);
DISPLAY 0.680851 (3338 2908);
PAINT GREEN (3338 2908);
FORCEPROP 2 LAST CDS_LIB standard
J 0
(3400 2900);
DISPLAY INVISIBLE (3400 2900);
FORCEPROP 1 LAST BODY_TYPE PLUMBING
J 0
(3400 2950);
DISPLAY 0.872340 (3400 2950);
PAINT GREEN (3400 2950);
DISPLAY INVISIBLE (3400 2950);
FORCEPROP 1 LAST HDL_TAP TRUE
J 0
(3725 2775);
DISPLAY 0.872340 (3725 2775);
DISPLAY INVISIBLE (3725 2775);
FORCEPROP 1 LAST PATH I500
J 0
(3398 2900);
DISPLAY 0.872340 (3398 2900);
PAINT GREEN (3398 2900);
DISPLAY INVISIBLE (3398 2900);
FORCEADD TAP..1
(3400 2650);
FORCEPROP 3 LASTPIN (3350 2650) SIG_NAME P5E_CPU1_PE0_TX_DN<4>
J 0
(3360 2660);
DISPLAY 0.659574 (3360 2660);
PAINT MONO (3360 2660);
DISPLAY INVISIBLE (3360 2660);
FORCEPROP 1 LASTPIN (3350 2650) BN 4
J 0
(3338 2658);
DISPLAY 0.680851 (3338 2658);
PAINT GREEN (3338 2658);
FORCEPROP 2 LAST CDS_LIB standard
J 0
(3400 2650);
PAINT MONO (3400 2650);
DISPLAY INVISIBLE (3400 2650);
FORCEPROP 1 LAST BODY_TYPE PLUMBING
J 0
(3400 2700);
DISPLAY 0.872340 (3400 2700);
PAINT GREEN (3400 2700);
DISPLAY INVISIBLE (3400 2700);
FORCEPROP 1 LAST HDL_TAP TRUE
J 0
(3725 2525);
DISPLAY 0.872340 (3725 2525);
DISPLAY INVISIBLE (3725 2525);
FORCEPROP 1 LAST PATH I501
J 0
(3398 2650);
DISPLAY 0.872340 (3398 2650);
PAINT GREEN (3398 2650);
DISPLAY INVISIBLE (3398 2650);
FORCEADD TAP..1
(3400 2750);
FORCEPROP 3 LASTPIN (3350 2750) SIG_NAME P5E_CPU1_PE0_TX_DN<6>
J 0
(3360 2760);
DISPLAY 0.659574 (3360 2760);
PAINT MONO (3360 2760);
DISPLAY INVISIBLE (3360 2760);
FORCEPROP 1 LASTPIN (3350 2750) BN 6
J 0
(3338 2758);
DISPLAY 0.680851 (3338 2758);
PAINT GREEN (3338 2758);
FORCEPROP 2 LAST CDS_LIB standard
J 0
(3400 2750);
PAINT MONO (3400 2750);
DISPLAY INVISIBLE (3400 2750);
FORCEPROP 1 LAST BODY_TYPE PLUMBING
J 0
(3400 2800);
DISPLAY 0.872340 (3400 2800);
PAINT GREEN (3400 2800);
DISPLAY INVISIBLE (3400 2800);
FORCEPROP 1 LAST HDL_TAP TRUE
J 0
(3725 2625);
DISPLAY 0.872340 (3725 2625);
DISPLAY INVISIBLE (3725 2625);
FORCEPROP 1 LAST PATH I502
J 0
(3398 2750);
DISPLAY 0.872340 (3398 2750);
PAINT GREEN (3398 2750);
DISPLAY INVISIBLE (3398 2750);
FORCEADD TAP..1
(3400 2700);
FORCEPROP 3 LASTPIN (3350 2700) SIG_NAME P5E_CPU1_PE0_TX_DN<5>
J 0
(3360 2710);
DISPLAY 0.659574 (3360 2710);
PAINT MONO (3360 2710);
DISPLAY INVISIBLE (3360 2710);
FORCEPROP 1 LASTPIN (3350 2700) BN 5
J 0
(3338 2708);
DISPLAY 0.680851 (3338 2708);
PAINT GREEN (3338 2708);
FORCEPROP 2 LAST CDS_LIB standard
J 0
(3400 2700);
PAINT MONO (3400 2700);
DISPLAY INVISIBLE (3400 2700);
FORCEPROP 1 LAST BODY_TYPE PLUMBING
J 0
(3400 2750);
DISPLAY 0.872340 (3400 2750);
PAINT GREEN (3400 2750);
DISPLAY INVISIBLE (3400 2750);
FORCEPROP 1 LAST HDL_TAP TRUE
J 0
(3725 2575);
DISPLAY 0.872340 (3725 2575);
DISPLAY INVISIBLE (3725 2575);
FORCEPROP 1 LAST PATH I503
J 0
(3398 2700);
DISPLAY 0.872340 (3398 2700);
PAINT GREEN (3398 2700);
DISPLAY INVISIBLE (3398 2700);
FORCEADD TAP..1
(3400 2600);
FORCEPROP 3 LASTPIN (3350 2600) SIG_NAME P5E_CPU1_PE0_TX_DN<3>
J 0
(3360 2610);
DISPLAY 0.659574 (3360 2610);
PAINT MONO (3360 2610);
DISPLAY INVISIBLE (3360 2610);
FORCEPROP 1 LASTPIN (3350 2600) BN 3
J 0
(3338 2608);
DISPLAY 0.680851 (3338 2608);
PAINT GREEN (3338 2608);
FORCEPROP 2 LAST CDS_LIB standard
J 0
(3400 2600);
PAINT MONO (3400 2600);
DISPLAY INVISIBLE (3400 2600);
FORCEPROP 1 LAST BODY_TYPE PLUMBING
J 0
(3400 2650);
DISPLAY 0.872340 (3400 2650);
PAINT GREEN (3400 2650);
DISPLAY INVISIBLE (3400 2650);
FORCEPROP 1 LAST HDL_TAP TRUE
J 0
(3725 2475);
DISPLAY 0.872340 (3725 2475);
DISPLAY INVISIBLE (3725 2475);
FORCEPROP 1 LAST PATH I504
J 0
(3398 2600);
DISPLAY 0.872340 (3398 2600);
PAINT GREEN (3398 2600);
DISPLAY INVISIBLE (3398 2600);
FORCEADD TAP..1
(3400 2550);
FORCEPROP 3 LASTPIN (3350 2550) SIG_NAME P5E_CPU1_PE0_TX_DN<2>
J 0
(3360 2560);
DISPLAY 0.659574 (3360 2560);
PAINT MONO (3360 2560);
DISPLAY INVISIBLE (3360 2560);
FORCEPROP 1 LASTPIN (3350 2550) BN 2
J 0
(3338 2558);
DISPLAY 0.680851 (3338 2558);
PAINT GREEN (3338 2558);
FORCEPROP 2 LAST CDS_LIB standard
J 0
(3400 2550);
PAINT MONO (3400 2550);
DISPLAY INVISIBLE (3400 2550);
FORCEPROP 1 LAST BODY_TYPE PLUMBING
J 0
(3400 2600);
DISPLAY 0.872340 (3400 2600);
PAINT GREEN (3400 2600);
DISPLAY INVISIBLE (3400 2600);
FORCEPROP 1 LAST HDL_TAP TRUE
J 0
(3725 2425);
DISPLAY 0.872340 (3725 2425);
DISPLAY INVISIBLE (3725 2425);
FORCEPROP 1 LAST PATH I505
J 0
(3398 2550);
DISPLAY 0.872340 (3398 2550);
PAINT GREEN (3398 2550);
DISPLAY INVISIBLE (3398 2550);
FORCEADD TAP..1
(3400 2500);
FORCEPROP 3 LASTPIN (3350 2500) SIG_NAME P5E_CPU1_PE0_TX_DN<1>
J 0
(3360 2510);
DISPLAY 0.659574 (3360 2510);
PAINT MONO (3360 2510);
DISPLAY INVISIBLE (3360 2510);
FORCEPROP 1 LASTPIN (3350 2500) BN 1
J 0
(3338 2508);
DISPLAY 0.680851 (3338 2508);
PAINT GREEN (3338 2508);
FORCEPROP 2 LAST CDS_LIB standard
J 0
(3400 2500);
PAINT MONO (3400 2500);
DISPLAY INVISIBLE (3400 2500);
FORCEPROP 1 LAST BODY_TYPE PLUMBING
J 0
(3400 2550);
DISPLAY 0.872340 (3400 2550);
PAINT GREEN (3400 2550);
DISPLAY INVISIBLE (3400 2550);
FORCEPROP 1 LAST HDL_TAP TRUE
J 0
(3725 2375);
DISPLAY 0.872340 (3725 2375);
DISPLAY INVISIBLE (3725 2375);
FORCEPROP 1 LAST PATH I506
J 0
(3398 2500);
DISPLAY 0.872340 (3398 2500);
PAINT GREEN (3398 2500);
DISPLAY INVISIBLE (3398 2500);
FORCEADD TAP..1
(3400 2450);
FORCEPROP 3 LASTPIN (3350 2450) SIG_NAME P5E_CPU1_PE0_TX_DN<0>
J 0
(3360 2460);
DISPLAY 0.659574 (3360 2460);
PAINT MONO (3360 2460);
DISPLAY INVISIBLE (3360 2460);
FORCEPROP 1 LASTPIN (3350 2450) BN 0
J 0
(3338 2458);
DISPLAY 0.680851 (3338 2458);
PAINT GREEN (3338 2458);
FORCEPROP 2 LAST CDS_LIB standard
J 0
(3400 2450);
PAINT MONO (3400 2450);
DISPLAY INVISIBLE (3400 2450);
FORCEPROP 1 LAST BODY_TYPE PLUMBING
J 0
(3400 2500);
DISPLAY 0.872340 (3400 2500);
PAINT GREEN (3400 2500);
DISPLAY INVISIBLE (3400 2500);
FORCEPROP 1 LAST HDL_TAP TRUE
J 0
(3725 2325);
DISPLAY 0.872340 (3725 2325);
DISPLAY INVISIBLE (3725 2325);
FORCEPROP 1 LAST PATH I507
J 0
(3398 2450);
DISPLAY 0.872340 (3398 2450);
PAINT GREEN (3398 2450);
DISPLAY INVISIBLE (3398 2450);
FORCEADD SOCKET4677_AZIF0045P001C01CS..18
(1675 475);
FORCEPROP 1 LAST PART_NUMBER DGA^7000023
J 0
(625 1525);
DISPLAY 0.723404 (625 1525);
PAINT GREEN (625 1525);
DISPLAY INVISIBLE (625 1525);
FORCEPROP 2 LAST VALUE SOCKET4677_AZIF0045-P001C01CS
J 0
(625 1650);
DISPLAY 1.021277 (625 1650);
FORCEPROP 1 LAST MATERIAL IO
J 0
(625 1450);
DISPLAY 0.723404 (625 1450);
PAINT GREEN (625 1450);
FORCEPROP 2 LAST PART_TYPE SMLF
J 0
(625 1700);
DISPLAY 1.021277 (625 1700);
FORCEPROP 1 LAST $LOCATION U1
J 0
(625 1600);
DISPLAY 0.723404 (625 1600);
PAINT GREEN (625 1600);
FORCEPROP 0 LASTPIN (475 -325) $PN CP10
J 2
(465 -315);
DISPLAY 0.680851 (465 -315);
PAINT MONO (465 -315);
FORCEPROP 0 LASTPIN (475 -275) $PN CL11
J 2
(465 -265);
DISPLAY 0.680851 (465 -265);
PAINT MONO (465 -265);
FORCEPROP 0 LASTPIN (475 -225) $PN CK10
J 2
(465 -215);
DISPLAY 0.680851 (465 -215);
PAINT MONO (465 -215);
FORCEPROP 0 LASTPIN (475 -175) $PN CG11
J 2
(465 -165);
DISPLAY 0.680851 (465 -165);
PAINT MONO (465 -165);
FORCEPROP 0 LASTPIN (475 -125) $PN CF10
J 2
(465 -115);
DISPLAY 0.680851 (465 -115);
PAINT MONO (465 -115);
FORCEPROP 0 LASTPIN (475 -75) $PN CC11
J 2
(465 -65);
DISPLAY 0.680851 (465 -65);
PAINT MONO (465 -65);
FORCEPROP 0 LASTPIN (475 -25) $PN CB10
J 2
(465 -15);
DISPLAY 0.680851 (465 -15);
PAINT MONO (465 -15);
FORCEPROP 0 LASTPIN (475 25) $PN BW11
J 2
(465 35);
DISPLAY 0.680851 (465 35);
PAINT MONO (465 35);
FORCEPROP 0 LASTPIN (475 75) $PN BV10
J 2
(465 85);
DISPLAY 0.680851 (465 85);
PAINT MONO (465 85);
FORCEPROP 0 LASTPIN (475 125) $PN BR11
J 2
(465 135);
DISPLAY 0.680851 (465 135);
PAINT MONO (465 135);
FORCEPROP 0 LASTPIN (475 175) $PN BP10
J 2
(465 185);
DISPLAY 0.680851 (465 185);
PAINT MONO (465 185);
FORCEPROP 0 LASTPIN (475 225) $PN BL11
J 2
(465 235);
DISPLAY 0.680851 (465 235);
PAINT MONO (465 235);
FORCEPROP 0 LASTPIN (475 275) $PN BK10
J 2
(465 285);
DISPLAY 0.680851 (465 285);
PAINT MONO (465 285);
FORCEPROP 0 LASTPIN (475 325) $PN BG11
J 2
(465 335);
DISPLAY 0.680851 (465 335);
PAINT MONO (465 335);
FORCEPROP 0 LASTPIN (475 375) $PN BF10
J 2
(465 385);
DISPLAY 0.680851 (465 385);
PAINT MONO (465 385);
FORCEPROP 0 LASTPIN (475 425) $PN BC11
J 2
(465 435);
DISPLAY 0.680851 (465 435);
PAINT MONO (465 435);
FORCEPROP 0 LASTPIN (475 525) $PN CN9
J 2
(465 535);
DISPLAY 0.680851 (465 535);
PAINT MONO (465 535);
FORCEPROP 0 LASTPIN (475 575) $PN CM10
J 2
(465 585);
DISPLAY 0.680851 (465 585);
PAINT MONO (465 585);
FORCEPROP 0 LASTPIN (475 625) $PN CJ9
J 2
(465 635);
DISPLAY 0.680851 (465 635);
PAINT MONO (465 635);
FORCEPROP 0 LASTPIN (475 675) $PN CH10
J 2
(465 685);
DISPLAY 0.680851 (465 685);
PAINT MONO (465 685);
FORCEPROP 0 LASTPIN (475 725) $PN CE9
J 2
(465 735);
DISPLAY 0.680851 (465 735);
PAINT MONO (465 735);
FORCEPROP 0 LASTPIN (475 775) $PN CD10
J 2
(465 785);
DISPLAY 0.680851 (465 785);
PAINT MONO (465 785);
FORCEPROP 0 LASTPIN (475 825) $PN CA9
J 2
(465 835);
DISPLAY 0.680851 (465 835);
PAINT MONO (465 835);
FORCEPROP 0 LASTPIN (475 875) $PN BY10
J 2
(465 885);
DISPLAY 0.680851 (465 885);
PAINT MONO (465 885);
FORCEPROP 0 LASTPIN (475 925) $PN BU9
J 2
(465 935);
DISPLAY 0.680851 (465 935);
PAINT MONO (465 935);
FORCEPROP 0 LASTPIN (475 975) $PN BT10
J 2
(465 985);
DISPLAY 0.680851 (465 985);
PAINT MONO (465 985);
FORCEPROP 0 LASTPIN (475 1025) $PN BN9
J 2
(465 1035);
DISPLAY 0.680851 (465 1035);
PAINT MONO (465 1035);
FORCEPROP 0 LASTPIN (475 1075) $PN BM10
J 2
(465 1085);
DISPLAY 0.680851 (465 1085);
PAINT MONO (465 1085);
FORCEPROP 0 LASTPIN (475 1125) $PN BJ9
J 2
(465 1135);
DISPLAY 0.680851 (465 1135);
PAINT MONO (465 1135);
FORCEPROP 0 LASTPIN (475 1175) $PN BH10
J 2
(465 1185);
DISPLAY 0.680851 (465 1185);
PAINT MONO (465 1185);
FORCEPROP 0 LASTPIN (475 1225) $PN BE9
J 2
(465 1235);
DISPLAY 0.680851 (465 1235);
PAINT MONO (465 1235);
FORCEPROP 0 LASTPIN (475 1275) $PN BD10
J 2
(465 1285);
DISPLAY 0.680851 (465 1285);
PAINT MONO (465 1285);
FORCEPROP 0 LASTPIN (2875 -325) $PN CP14
J 0
(2885 -315);
DISPLAY 0.680851 (2885 -315);
PAINT MONO (2885 -315);
FORCEPROP 0 LASTPIN (2875 -275) $PN CN13
J 0
(2885 -265);
DISPLAY 0.680851 (2885 -265);
PAINT MONO (2885 -265);
FORCEPROP 0 LASTPIN (2875 -225) $PN CK14
J 0
(2885 -215);
DISPLAY 0.680851 (2885 -215);
PAINT MONO (2885 -215);
FORCEPROP 0 LASTPIN (2875 -175) $PN CJ13
J 0
(2885 -165);
DISPLAY 0.680851 (2885 -165);
PAINT MONO (2885 -165);
FORCEPROP 0 LASTPIN (2875 -125) $PN CF14
J 0
(2885 -115);
DISPLAY 0.680851 (2885 -115);
PAINT MONO (2885 -115);
FORCEPROP 0 LASTPIN (2875 -75) $PN CE13
J 0
(2885 -65);
DISPLAY 0.680851 (2885 -65);
PAINT MONO (2885 -65);
FORCEPROP 0 LASTPIN (2875 -25) $PN CB14
J 0
(2885 -15);
DISPLAY 0.680851 (2885 -15);
PAINT MONO (2885 -15);
FORCEPROP 0 LASTPIN (2875 25) $PN CA13
J 0
(2885 35);
DISPLAY 0.680851 (2885 35);
PAINT MONO (2885 35);
FORCEPROP 0 LASTPIN (2875 75) $PN BV14
J 0
(2885 85);
DISPLAY 0.680851 (2885 85);
PAINT MONO (2885 85);
FORCEPROP 0 LASTPIN (2875 125) $PN BU13
J 0
(2885 135);
DISPLAY 0.680851 (2885 135);
PAINT MONO (2885 135);
FORCEPROP 0 LASTPIN (2875 175) $PN BP14
J 0
(2885 185);
DISPLAY 0.680851 (2885 185);
PAINT MONO (2885 185);
FORCEPROP 0 LASTPIN (2875 225) $PN BN13
J 0
(2885 235);
DISPLAY 0.680851 (2885 235);
PAINT MONO (2885 235);
FORCEPROP 0 LASTPIN (2875 275) $PN BK14
J 0
(2885 285);
DISPLAY 0.680851 (2885 285);
PAINT MONO (2885 285);
FORCEPROP 0 LASTPIN (2875 325) $PN BJ13
J 0
(2885 335);
DISPLAY 0.680851 (2885 335);
PAINT MONO (2885 335);
FORCEPROP 0 LASTPIN (2875 375) $PN BF14
J 0
(2885 385);
DISPLAY 0.680851 (2885 385);
PAINT MONO (2885 385);
FORCEPROP 0 LASTPIN (2875 425) $PN BE13
J 0
(2885 435);
DISPLAY 0.680851 (2885 435);
PAINT MONO (2885 435);
FORCEPROP 0 LASTPIN (2875 525) $PN CR15
J 0
(2885 535);
DISPLAY 0.680851 (2885 535);
PAINT MONO (2885 535);
FORCEPROP 0 LASTPIN (2875 575) $PN CM14
J 0
(2885 585);
DISPLAY 0.680851 (2885 585);
PAINT MONO (2885 585);
FORCEPROP 0 LASTPIN (2875 625) $PN CL15
J 0
(2885 635);
DISPLAY 0.680851 (2885 635);
PAINT MONO (2885 635);
FORCEPROP 0 LASTPIN (2875 675) $PN CH14
J 0
(2885 685);
DISPLAY 0.680851 (2885 685);
PAINT MONO (2885 685);
FORCEPROP 0 LASTPIN (2875 725) $PN CG15
J 0
(2885 735);
DISPLAY 0.680851 (2885 735);
PAINT MONO (2885 735);
FORCEPROP 0 LASTPIN (2875 775) $PN CD14
J 0
(2885 785);
DISPLAY 0.680851 (2885 785);
PAINT MONO (2885 785);
FORCEPROP 0 LASTPIN (2875 825) $PN CC15
J 0
(2885 835);
DISPLAY 0.680851 (2885 835);
PAINT MONO (2885 835);
FORCEPROP 0 LASTPIN (2875 875) $PN BY14
J 0
(2885 885);
DISPLAY 0.680851 (2885 885);
PAINT MONO (2885 885);
FORCEPROP 0 LASTPIN (2875 925) $PN BW15
J 0
(2885 935);
DISPLAY 0.680851 (2885 935);
PAINT MONO (2885 935);
FORCEPROP 0 LASTPIN (2875 975) $PN BT14
J 0
(2885 985);
DISPLAY 0.680851 (2885 985);
PAINT MONO (2885 985);
FORCEPROP 0 LASTPIN (2875 1025) $PN BR15
J 0
(2885 1035);
DISPLAY 0.680851 (2885 1035);
PAINT MONO (2885 1035);
FORCEPROP 0 LASTPIN (2875 1075) $PN BM14
J 0
(2885 1085);
DISPLAY 0.680851 (2885 1085);
PAINT MONO (2885 1085);
FORCEPROP 0 LASTPIN (2875 1125) $PN BL15
J 0
(2885 1135);
DISPLAY 0.680851 (2885 1135);
PAINT MONO (2885 1135);
FORCEPROP 0 LASTPIN (2875 1175) $PN BH14
J 0
(2885 1185);
DISPLAY 0.680851 (2885 1185);
PAINT MONO (2885 1185);
FORCEPROP 0 LASTPIN (2875 1225) $PN BG15
J 0
(2885 1235);
DISPLAY 0.680851 (2885 1235);
PAINT MONO (2885 1235);
FORCEPROP 0 LASTPIN (2875 1275) $PN BD14
J 0
(2885 1285);
DISPLAY 0.680851 (2885 1285);
PAINT MONO (2885 1285);
FORCEPROP 1 LAST CDS_LMAN_SYM_OUTLINE -1050,950,1050,-950
J 0
(1675 475);
DISPLAY 0.468085 (1675 475);
PAINT GREEN (1675 475);
DISPLAY INVISIBLE (1675 475);
FORCEPROP 1 LAST NEEDS_NO_SIZE TRUE
J 0
(1675 475);
DISPLAY 0.723404 (1675 475);
PAINT GREEN (1675 475);
DISPLAY INVISIBLE (1675 475);
FORCEPROP 2 LAST CDS_LIB pure_quanta
J 0
(1675 475);
DISPLAY INVISIBLE (1675 475);
FORCEPROP 2 LAST CDS_LOCATION U1
J 0
(625 1750);
DISPLAY 1.021277 (625 1750);
DISPLAY INVISIBLE (625 1750);
FORCEPROP 0 LAST $SEC 18
J 0
(625 1750);
DISPLAY 0.680851 (625 1750);
PAINT MONO (625 1750);
DISPLAY INVISIBLE (625 1750);
FORCEPROP 2 LAST CDS_SEC 18
J 0
(625 1750);
DISPLAY 1.021277 (625 1750);
DISPLAY INVISIBLE (625 1750);
FORCEPROP 1 LAST PATH I69
J 0
(1675 475);
DISPLAY 0.723404 (1675 475);
PAINT GREEN (1675 475);
DISPLAY INVISIBLE (1675 475);
FORCEADD SOCKET4677_AZIF0045P001C01CS..17
(1675 3250);
FORCEPROP 1 LAST PART_NUMBER DGA^7000023
J 0
(625 4300);
DISPLAY 0.723404 (625 4300);
PAINT GREEN (625 4300);
DISPLAY INVISIBLE (625 4300);
FORCEPROP 2 LAST VALUE SOCKET4677_AZIF0045-P001C01CS
J 0
(625 4425);
DISPLAY 1.021277 (625 4425);
FORCEPROP 1 LAST MATERIAL IO
J 0
(625 4225);
DISPLAY 0.723404 (625 4225);
PAINT GREEN (625 4225);
FORCEPROP 2 LAST PART_TYPE SMLF
J 0
(625 4475);
DISPLAY 1.021277 (625 4475);
FORCEPROP 1 LAST $LOCATION U1
J 0
(625 4375);
DISPLAY 0.723404 (625 4375);
PAINT GREEN (625 4375);
FORCEPROP 0 LASTPIN (475 2450) $PN K10
J 2
(465 2460);
DISPLAY 0.680851 (465 2460);
PAINT MONO (465 2460);
FORCEPROP 0 LASTPIN (475 2500) $PN M10
J 2
(465 2510);
DISPLAY 0.680851 (465 2510);
PAINT MONO (465 2510);
FORCEPROP 0 LASTPIN (475 2550) $PN P10
J 2
(465 2560);
DISPLAY 0.680851 (465 2560);
PAINT MONO (465 2560);
FORCEPROP 0 LASTPIN (475 2600) $PN T10
J 2
(465 2610);
DISPLAY 0.680851 (465 2610);
PAINT MONO (465 2610);
FORCEPROP 0 LASTPIN (475 2650) $PN V10
J 2
(465 2660);
DISPLAY 0.680851 (465 2660);
PAINT MONO (465 2660);
FORCEPROP 0 LASTPIN (475 2700) $PN AA9
J 2
(465 2710);
DISPLAY 0.680851 (465 2710);
PAINT MONO (465 2710);
FORCEPROP 0 LASTPIN (475 2750) $PN AB10
J 2
(465 2760);
DISPLAY 0.680851 (465 2760);
PAINT MONO (465 2760);
FORCEPROP 0 LASTPIN (475 2800) $PN AE9
J 2
(465 2810);
DISPLAY 0.680851 (465 2810);
PAINT MONO (465 2810);
FORCEPROP 0 LASTPIN (475 2850) $PN AF10
J 2
(465 2860);
DISPLAY 0.680851 (465 2860);
PAINT MONO (465 2860);
FORCEPROP 0 LASTPIN (475 2900) $PN AJ9
J 2
(465 2910);
DISPLAY 0.680851 (465 2910);
PAINT MONO (465 2910);
FORCEPROP 0 LASTPIN (475 2950) $PN AK10
J 2
(465 2960);
DISPLAY 0.680851 (465 2960);
PAINT MONO (465 2960);
FORCEPROP 0 LASTPIN (475 3000) $PN AM10
J 2
(465 3010);
DISPLAY 0.680851 (465 3010);
PAINT MONO (465 3010);
FORCEPROP 0 LASTPIN (475 3050) $PN AP10
J 2
(465 3060);
DISPLAY 0.680851 (465 3060);
PAINT MONO (465 3060);
FORCEPROP 0 LASTPIN (475 3100) $PN AU9
J 2
(465 3110);
DISPLAY 0.680851 (465 3110);
PAINT MONO (465 3110);
FORCEPROP 0 LASTPIN (475 3150) $PN AV10
J 2
(465 3160);
DISPLAY 0.680851 (465 3160);
PAINT MONO (465 3160);
FORCEPROP 0 LASTPIN (475 3200) $PN BA9
J 2
(465 3210);
DISPLAY 0.680851 (465 3210);
PAINT MONO (465 3210);
FORCEPROP 0 LASTPIN (475 3300) $PN L11
J 2
(465 3310);
DISPLAY 0.680851 (465 3310);
PAINT MONO (465 3310);
FORCEPROP 0 LASTPIN (475 3350) $PN N9
J 2
(465 3360);
DISPLAY 0.680851 (465 3360);
PAINT MONO (465 3360);
FORCEPROP 0 LASTPIN (475 3400) $PN R11
J 2
(465 3410);
DISPLAY 0.680851 (465 3410);
PAINT MONO (465 3410);
FORCEPROP 0 LASTPIN (475 3450) $PN U9
J 2
(465 3460);
DISPLAY 0.680851 (465 3460);
PAINT MONO (465 3460);
FORCEPROP 0 LASTPIN (475 3500) $PN W11
J 2
(465 3510);
DISPLAY 0.680851 (465 3510);
PAINT MONO (465 3510);
FORCEPROP 0 LASTPIN (475 3550) $PN Y10
J 2
(465 3560);
DISPLAY 0.680851 (465 3560);
PAINT MONO (465 3560);
FORCEPROP 0 LASTPIN (475 3600) $PN AC11
J 2
(465 3610);
DISPLAY 0.680851 (465 3610);
PAINT MONO (465 3610);
FORCEPROP 0 LASTPIN (475 3650) $PN AD10
J 2
(465 3660);
DISPLAY 0.680851 (465 3660);
PAINT MONO (465 3660);
FORCEPROP 0 LASTPIN (475 3700) $PN AG11
J 2
(465 3710);
DISPLAY 0.680851 (465 3710);
PAINT MONO (465 3710);
FORCEPROP 0 LASTPIN (475 3750) $PN AH10
J 2
(465 3760);
DISPLAY 0.680851 (465 3760);
PAINT MONO (465 3760);
FORCEPROP 0 LASTPIN (475 3800) $PN AL11
J 2
(465 3810);
DISPLAY 0.680851 (465 3810);
PAINT MONO (465 3810);
FORCEPROP 0 LASTPIN (475 3850) $PN AN9
J 2
(465 3860);
DISPLAY 0.680851 (465 3860);
PAINT MONO (465 3860);
FORCEPROP 0 LASTPIN (475 3900) $PN AR11
J 2
(465 3910);
DISPLAY 0.680851 (465 3910);
PAINT MONO (465 3910);
FORCEPROP 0 LASTPIN (475 3950) $PN AT10
J 2
(465 3960);
DISPLAY 0.680851 (465 3960);
PAINT MONO (465 3960);
FORCEPROP 0 LASTPIN (475 4000) $PN AW11
J 2
(465 4010);
DISPLAY 0.680851 (465 4010);
PAINT MONO (465 4010);
FORCEPROP 0 LASTPIN (475 4050) $PN AY10
J 2
(465 4060);
DISPLAY 0.680851 (465 4060);
PAINT MONO (465 4060);
FORCEPROP 0 LASTPIN (2875 2450) $PN N13
J 0
(2885 2460);
DISPLAY 0.680851 (2885 2460);
PAINT MONO (2885 2460);
FORCEPROP 0 LASTPIN (2875 2500) $PN P14
J 0
(2885 2510);
DISPLAY 0.680851 (2885 2510);
PAINT MONO (2885 2510);
FORCEPROP 0 LASTPIN (2875 2550) $PN U13
J 0
(2885 2560);
DISPLAY 0.680851 (2885 2560);
PAINT MONO (2885 2560);
FORCEPROP 0 LASTPIN (2875 2600) $PN V14
J 0
(2885 2610);
DISPLAY 0.680851 (2885 2610);
PAINT MONO (2885 2610);
FORCEPROP 0 LASTPIN (2875 2650) $PN AA13
J 0
(2885 2660);
DISPLAY 0.680851 (2885 2660);
PAINT MONO (2885 2660);
FORCEPROP 0 LASTPIN (2875 2700) $PN AB14
J 0
(2885 2710);
DISPLAY 0.680851 (2885 2710);
PAINT MONO (2885 2710);
FORCEPROP 0 LASTPIN (2875 2750) $PN AE13
J 0
(2885 2760);
DISPLAY 0.680851 (2885 2760);
PAINT MONO (2885 2760);
FORCEPROP 0 LASTPIN (2875 2800) $PN AF14
J 0
(2885 2810);
DISPLAY 0.680851 (2885 2810);
PAINT MONO (2885 2810);
FORCEPROP 0 LASTPIN (2875 2850) $PN AJ13
J 0
(2885 2860);
DISPLAY 0.680851 (2885 2860);
PAINT MONO (2885 2860);
FORCEPROP 0 LASTPIN (2875 2900) $PN AK14
J 0
(2885 2910);
DISPLAY 0.680851 (2885 2910);
PAINT MONO (2885 2910);
FORCEPROP 0 LASTPIN (2875 2950) $PN AN13
J 0
(2885 2960);
DISPLAY 0.680851 (2885 2960);
PAINT MONO (2885 2960);
FORCEPROP 0 LASTPIN (2875 3000) $PN AP14
J 0
(2885 3010);
DISPLAY 0.680851 (2885 3010);
PAINT MONO (2885 3010);
FORCEPROP 0 LASTPIN (2875 3050) $PN AU13
J 0
(2885 3060);
DISPLAY 0.680851 (2885 3060);
PAINT MONO (2885 3060);
FORCEPROP 0 LASTPIN (2875 3100) $PN AV14
J 0
(2885 3110);
DISPLAY 0.680851 (2885 3110);
PAINT MONO (2885 3110);
FORCEPROP 0 LASTPIN (2875 3150) $PN BA13
J 0
(2885 3160);
DISPLAY 0.680851 (2885 3160);
PAINT MONO (2885 3160);
FORCEPROP 0 LASTPIN (2875 3200) $PN BB14
J 0
(2885 3210);
DISPLAY 0.680851 (2885 3210);
PAINT MONO (2885 3210);
FORCEPROP 0 LASTPIN (2875 3300) $PN M14
J 0
(2885 3310);
DISPLAY 0.680851 (2885 3310);
PAINT MONO (2885 3310);
FORCEPROP 0 LASTPIN (2875 3350) $PN R15
J 0
(2885 3360);
DISPLAY 0.680851 (2885 3360);
PAINT MONO (2885 3360);
FORCEPROP 0 LASTPIN (2875 3400) $PN T14
J 0
(2885 3410);
DISPLAY 0.680851 (2885 3410);
PAINT MONO (2885 3410);
FORCEPROP 0 LASTPIN (2875 3450) $PN W15
J 0
(2885 3460);
DISPLAY 0.680851 (2885 3460);
PAINT MONO (2885 3460);
FORCEPROP 0 LASTPIN (2875 3500) $PN Y14
J 0
(2885 3510);
DISPLAY 0.680851 (2885 3510);
PAINT MONO (2885 3510);
FORCEPROP 0 LASTPIN (2875 3550) $PN AC15
J 0
(2885 3560);
DISPLAY 0.680851 (2885 3560);
PAINT MONO (2885 3560);
FORCEPROP 0 LASTPIN (2875 3600) $PN AD14
J 0
(2885 3610);
DISPLAY 0.680851 (2885 3610);
PAINT MONO (2885 3610);
FORCEPROP 0 LASTPIN (2875 3650) $PN AG15
J 0
(2885 3660);
DISPLAY 0.680851 (2885 3660);
PAINT MONO (2885 3660);
FORCEPROP 0 LASTPIN (2875 3700) $PN AH14
J 0
(2885 3710);
DISPLAY 0.680851 (2885 3710);
PAINT MONO (2885 3710);
FORCEPROP 0 LASTPIN (2875 3750) $PN AL15
J 0
(2885 3760);
DISPLAY 0.680851 (2885 3760);
PAINT MONO (2885 3760);
FORCEPROP 0 LASTPIN (2875 3800) $PN AM14
J 0
(2885 3810);
DISPLAY 0.680851 (2885 3810);
PAINT MONO (2885 3810);
FORCEPROP 0 LASTPIN (2875 3850) $PN AR15
J 0
(2885 3860);
DISPLAY 0.680851 (2885 3860);
PAINT MONO (2885 3860);
FORCEPROP 0 LASTPIN (2875 3900) $PN AT14
J 0
(2885 3910);
DISPLAY 0.680851 (2885 3910);
PAINT MONO (2885 3910);
FORCEPROP 0 LASTPIN (2875 3950) $PN AW15
J 0
(2885 3960);
DISPLAY 0.680851 (2885 3960);
PAINT MONO (2885 3960);
FORCEPROP 0 LASTPIN (2875 4000) $PN AY14
J 0
(2885 4010);
DISPLAY 0.680851 (2885 4010);
PAINT MONO (2885 4010);
FORCEPROP 0 LASTPIN (2875 4050) $PN BC15
J 0
(2885 4060);
DISPLAY 0.680851 (2885 4060);
PAINT MONO (2885 4060);
FORCEPROP 1 LAST CDS_LMAN_SYM_OUTLINE -1050,950,1050,-950
J 0
(1675 3250);
DISPLAY 0.468085 (1675 3250);
PAINT GREEN (1675 3250);
DISPLAY INVISIBLE (1675 3250);
FORCEPROP 1 LAST NEEDS_NO_SIZE TRUE
J 0
(1675 3250);
DISPLAY 0.723404 (1675 3250);
PAINT GREEN (1675 3250);
DISPLAY INVISIBLE (1675 3250);
FORCEPROP 2 LAST CDS_LIB pure_quanta
J 0
(1675 3250);
DISPLAY INVISIBLE (1675 3250);
FORCEPROP 2 LAST CDS_LOCATION U1
J 0
(625 4525);
DISPLAY 1.021277 (625 4525);
DISPLAY INVISIBLE (625 4525);
FORCEPROP 0 LAST $SEC 17
J 0
(625 4525);
DISPLAY 0.680851 (625 4525);
PAINT MONO (625 4525);
DISPLAY INVISIBLE (625 4525);
FORCEPROP 2 LAST CDS_SEC 17
J 0
(625 4525);
DISPLAY 1.021277 (625 4525);
DISPLAY INVISIBLE (625 4525);
FORCEPROP 1 LAST PATH I80
J 0
(1675 3250);
DISPLAY 0.723404 (1675 3250);
PAINT GREEN (1675 3250);
DISPLAY INVISIBLE (1675 3250);
FORCEADD QUANTA_TITLE_BLOCK_C..1
(6275 -1450);
FORCEPROP 0 LAST CDS_CON_LAST_MODIFIED Fri Aug 25 14:00:42 2023
J 0
(4390 -1435);
PAINT MONO (4390 -1435);
DISPLAY INVISIBLE (4390 -1435);
FORCEPROP 1 LAST CUSTOM_TXT_CDS <CON_LAST_MODIFIED>
J 0
(4390 -1435);
DISPLAY 0.978723 (4390 -1435);
FORCEPROP 2 LAST CUSTOM_TXT_CDS <XR_PAGE_TITLE>
J 0
(-1615 3800);
DISPLAY 0.638298 (-1615 3800);
PAINT PINK (-1615 3800);
DISPLAY INVISIBLE (-1615 3800);
FORCEPROP 2 LAST CUSTOM_TXT_CDS <Q_NUMBER>
J 0
(4872 -1347);
DISPLAY 1.212766 (4872 -1347);
FORCEPROP 1 LAST CUSTOM_TXT_CDS <NAME_2>
J 0
(3100 -1400);
FORCEPROP 1 LAST CUSTOM_TXT_CDS <NAME_1>
J 0
(3100 -1275);
FORCEPROP 1 LAST CUSTOM_TXT_CDS <Q_PROJ>
J 0
(3893 -1348);
DISPLAY 1.212766 (3893 -1348);
FORCEPROP 1 LAST CUSTOM_TXT_CDS <Q_REV>
J 0
(6091 -1347);
DISPLAY 1.212766 (6091 -1347);
FORCEPROP 1 LAST CUSTOM_TXT_CDS <CON_PAGE_NUM> OF <CON_TOTAL_PAGES>
J 0
(5829 -1432);
DISPLAY 0.978723 (5829 -1432);
FORCEPROP 1 LAST Q_TITLE SPR CPU1 - PCIE PE0/PE1 (17 OF 30)
J 0
(-3091 -1424);
DISPLAY 1.957447 (-3091 -1424);
PAINT GREEN (-3091 -1424);
FORCEPROP 1 LAST Q_DEPT 
J 1
(2512 -1401);
DISPLAY 1.957447 (2512 -1401);
PAINT GREEN (2512 -1401);
FORCEPROP 1 LAST COMMENT_BODY TRUE
J 0
(6287 -1463);
DISPLAY 0.978723 (6287 -1463);
PAINT GREEN (6287 -1463);
DISPLAY INVISIBLE (6287 -1463);
FORCEPROP 2 LAST CDS_XR_PAGE_TITLE CR-60 : @S9S_MB_2U_LIB.S9S_MB_2U(SCH_1):PAGE60
J 0
(-1615 3800);
DISPLAY 0.638298 (-1615 3800);
PAINT PINK (-1615 3800);
DISPLAY INVISIBLE (-1615 3800);
FORCEPROP 2 LAST PAGE_BORDER TRUE
J 0
(-1615 3800);
DISPLAY 0.638298 (-1615 3800);
PAINT PINK (-1615 3800);
DISPLAY INVISIBLE (-1615 3800);
FORCEPROP 1 LAST CDS_LMAN_SYM_OUTLINE -9475,6775,100,-125
J 0
(6275 -1450);
DISPLAY 0.468085 (6275 -1450);
PAINT GREEN (6275 -1450);
DISPLAY INVISIBLE (6275 -1450);
FORCEPROP 2 LAST CDS_LIB pure_quanta
J 0
(6275 -1450);
PAINT MONO (6275 -1450);
DISPLAY INVISIBLE (6275 -1450);
WIRE 17 -1 (3450 550)(3450 600);
WIRE 17 -1 (3450 600)(3450 650);
WIRE 17 -1 (3450 650)(3450 700);
WIRE 17 -1 (3450 700)(3450 750);
WIRE 17 -1 (3450 750)(3450 800);
WIRE 17 -1 (3450 800)(3450 850);
WIRE 17 -1 (3450 850)(3450 900);
WIRE 17 -1 (3450 900)(3450 950);
WIRE 17 -1 (3450 950)(3450 1000);
WIRE 17 -1 (3450 1000)(3450 1050);
WIRE 17 -1 (3450 1050)(3450 1100);
WIRE 17 -1 (3450 1100)(3450 1150);
WIRE 17 -1 (3450 1150)(3450 1200);
WIRE 17 -1 (3450 1200)(3450 1250);
WIRE 17 -1 (3450 1250)(3450 1300);
WIRE 17 -1 (3450 1300)(4450 1300);
FORCEPROP 2 LAST SIG_NAME P5E_CPU1_PE1_TX_DP<15:0>
J 0
(3590 1310);
DISPLAY 0.680851 (3590 1310);
PAINT WHITE (3590 1310);
WIRE 17 -1 (3450 -300)(3450 -250);
WIRE 17 -1 (3450 -250)(3450 -200);
WIRE 17 -1 (3450 -200)(3450 -150);
WIRE 17 -1 (3450 -150)(3450 -100);
WIRE 17 -1 (3450 -100)(3450 -50);
WIRE 17 -1 (3450 -50)(3450 0);
WIRE 17 -1 (3450 0)(3450 50);
WIRE 17 -1 (3450 50)(3450 100);
WIRE 17 -1 (3450 100)(3450 150);
WIRE 17 -1 (3450 150)(3450 200);
WIRE 17 -1 (3450 200)(3450 250);
WIRE 17 -1 (3450 250)(3450 300);
WIRE 17 -1 (3450 300)(3450 350);
WIRE 17 -1 (3450 350)(3450 400);
WIRE 17 -1 (3450 400)(3450 450);
WIRE 17 -1 (3450 450)(4450 450);
FORCEPROP 2 LAST SIG_NAME P5E_CPU1_PE1_TX_DN<15:0>
J 0
(3590 460);
DISPLAY 0.680851 (3590 460);
PAINT WHITE (3590 460);
WIRE 17 -1 (-75 550)(-75 600);
WIRE 17 -1 (-75 600)(-75 650);
WIRE 17 -1 (-75 650)(-75 700);
WIRE 17 -1 (-75 700)(-75 750);
WIRE 17 -1 (-75 750)(-75 800);
WIRE 17 -1 (-75 800)(-75 850);
WIRE 17 -1 (-75 850)(-75 900);
WIRE 17 -1 (-75 900)(-75 950);
WIRE 17 -1 (-75 950)(-75 1000);
WIRE 17 -1 (-75 1000)(-75 1050);
WIRE 17 -1 (-75 1050)(-75 1100);
WIRE 17 -1 (-75 1100)(-75 1150);
WIRE 17 -1 (-75 1150)(-75 1200);
WIRE 17 -1 (-75 1200)(-75 1250);
WIRE 17 -1 (-75 1250)(-75 1300);
WIRE 17 -1 (-1225 1300)(-75 1300);
FORCEPROP 2 LAST SIG_NAME P5E_CPU1_PE1_RX_DP<15:0>
J 0
(-1110 1310);
DISPLAY 0.680851 (-1110 1310);
PAINT WHITE (-1110 1310);
WIRE 17 -1 (-75 -300)(-75 -250);
WIRE 17 -1 (-75 -250)(-75 -200);
WIRE 17 -1 (-75 -200)(-75 -150);
WIRE 17 -1 (-75 -150)(-75 -100);
WIRE 17 -1 (-75 -100)(-75 -50);
WIRE 17 -1 (-75 -50)(-75 0);
WIRE 17 -1 (-75 0)(-75 50);
WIRE 17 -1 (-75 50)(-75 100);
WIRE 17 -1 (-75 100)(-75 150);
WIRE 17 -1 (-75 150)(-75 200);
WIRE 17 -1 (-75 200)(-75 250);
WIRE 17 -1 (-75 250)(-75 300);
WIRE 17 -1 (-75 300)(-75 350);
WIRE 17 -1 (-75 350)(-75 400);
WIRE 17 -1 (-75 400)(-75 450);
WIRE 17 -1 (-1225 450)(-75 450);
FORCEPROP 2 LAST SIG_NAME P5E_CPU1_PE1_RX_DN<15:0>
J 0
(-1110 460);
DISPLAY 0.680851 (-1110 460);
PAINT WHITE (-1110 460);
WIRE 17 -1 (3450 3325)(3450 3375);
WIRE 17 -1 (3450 3375)(3450 3425);
WIRE 17 -1 (3450 3425)(3450 3475);
WIRE 17 -1 (3450 3475)(3450 3525);
WIRE 17 -1 (3450 3525)(3450 3575);
WIRE 17 -1 (3450 3575)(3450 3625);
WIRE 17 -1 (3450 3625)(3450 3675);
WIRE 17 -1 (3450 3675)(3450 3725);
WIRE 17 -1 (3450 3725)(3450 3775);
WIRE 17 -1 (3450 3775)(3450 3825);
WIRE 17 -1 (3450 3825)(3450 3875);
WIRE 17 -1 (3450 3875)(3450 3925);
WIRE 17 -1 (3450 3925)(3450 3975);
WIRE 17 -1 (3450 3975)(3450 4025);
WIRE 17 -1 (3450 4025)(3450 4075);
WIRE 17 -1 (3450 4075)(4450 4075);
FORCEPROP 2 LAST SIG_NAME P5E_CPU1_PE0_TX_DP<15:0>
J 0
(3590 4085);
DISPLAY 0.680851 (3590 4085);
PAINT WHITE (3590 4085);
WIRE 17 -1 (3450 2475)(3450 2525);
WIRE 17 -1 (3450 2525)(3450 2575);
WIRE 17 -1 (3450 2575)(3450 2625);
WIRE 17 -1 (3450 2625)(3450 2675);
WIRE 17 -1 (3450 2675)(3450 2725);
WIRE 17 -1 (3450 2725)(3450 2775);
WIRE 17 -1 (3450 2775)(3450 2825);
WIRE 17 -1 (3450 2825)(3450 2875);
WIRE 17 -1 (3450 2875)(3450 2925);
WIRE 17 -1 (3450 2925)(3450 2975);
WIRE 17 -1 (3450 2975)(3450 3025);
WIRE 17 -1 (3450 3025)(3450 3075);
WIRE 17 -1 (3450 3075)(3450 3125);
WIRE 17 -1 (3450 3125)(3450 3175);
WIRE 17 -1 (3450 3175)(3450 3225);
WIRE 17 -1 (3450 3225)(4450 3225);
FORCEPROP 2 LAST SIG_NAME P5E_CPU1_PE0_TX_DN<15:0>
J 0
(3590 3235);
DISPLAY 0.680851 (3590 3235);
PAINT WHITE (3590 3235);
WIRE 17 -1 (-75 3325)(-75 3375);
WIRE 17 -1 (-75 3375)(-75 3425);
WIRE 17 -1 (-75 3425)(-75 3475);
WIRE 17 -1 (-75 3475)(-75 3525);
WIRE 17 -1 (-75 3525)(-75 3575);
WIRE 17 -1 (-75 3575)(-75 3625);
WIRE 17 -1 (-75 3625)(-75 3675);
WIRE 17 -1 (-75 3675)(-75 3725);
WIRE 17 -1 (-75 3725)(-75 3775);
WIRE 17 -1 (-75 3775)(-75 3825);
WIRE 17 -1 (-75 3825)(-75 3875);
WIRE 17 -1 (-75 3875)(-75 3925);
WIRE 17 -1 (-75 3925)(-75 3975);
WIRE 17 -1 (-75 3975)(-75 4025);
WIRE 17 -1 (-75 4025)(-75 4075);
WIRE 17 -1 (-1225 4075)(-75 4075);
FORCEPROP 2 LAST SIG_NAME P5E_CPU1_PE0_RX_DP<15:0>
J 0
(-1110 4085);
DISPLAY 0.680851 (-1110 4085);
PAINT WHITE (-1110 4085);
WIRE 17 -1 (-75 2475)(-75 2525);
WIRE 17 -1 (-75 2525)(-75 2575);
WIRE 17 -1 (-75 2575)(-75 2625);
WIRE 17 -1 (-75 2625)(-75 2675);
WIRE 17 -1 (-75 2675)(-75 2725);
WIRE 17 -1 (-75 2725)(-75 2775);
WIRE 17 -1 (-75 2775)(-75 2825);
WIRE 17 -1 (-75 2825)(-75 2875);
WIRE 17 -1 (-75 2875)(-75 2925);
WIRE 17 -1 (-75 2925)(-75 2975);
WIRE 17 -1 (-75 2975)(-75 3025);
WIRE 17 -1 (-75 3025)(-75 3075);
WIRE 17 -1 (-75 3075)(-75 3125);
WIRE 17 -1 (-75 3125)(-75 3175);
WIRE 17 -1 (-75 3175)(-75 3225);
WIRE 17 -1 (-1225 3225)(-75 3225);
FORCEPROP 2 LAST SIG_NAME P5E_CPU1_PE0_RX_DN<15:0>
J 0
(-1110 3235);
DISPLAY 0.680851 (-1110 3235);
PAINT WHITE (-1110 3235);
WIRE 16 -1 (25 3200)(475 3200);
WIRE 16 -1 (25 3150)(475 3150);
WIRE 16 -1 (25 3100)(475 3100);
WIRE 16 -1 (25 3050)(475 3050);
WIRE 16 -1 (25 3000)(475 3000);
WIRE 16 -1 (25 2950)(475 2950);
WIRE 16 -1 (25 2900)(475 2900);
WIRE 16 -1 (25 2850)(475 2850);
WIRE 16 -1 (25 2800)(475 2800);
WIRE 16 -1 (25 2750)(475 2750);
WIRE 16 -1 (25 2700)(475 2700);
WIRE 16 -1 (25 2650)(475 2650);
WIRE 16 -1 (25 2600)(475 2600);
WIRE 16 -1 (25 2550)(475 2550);
WIRE 16 -1 (25 2500)(475 2500);
WIRE 16 -1 (25 2450)(475 2450);
WIRE 16 -1 (25 4050)(475 4050);
WIRE 16 -1 (25 4000)(475 4000);
WIRE 16 -1 (25 3950)(475 3950);
WIRE 16 -1 (25 3900)(475 3900);
WIRE 16 -1 (25 3850)(475 3850);
WIRE 16 -1 (25 3800)(475 3800);
WIRE 16 -1 (25 3750)(475 3750);
WIRE 16 -1 (25 3700)(475 3700);
WIRE 16 -1 (25 3650)(475 3650);
WIRE 16 -1 (25 3600)(475 3600);
WIRE 16 -1 (25 3550)(475 3550);
WIRE 16 -1 (25 3500)(475 3500);
WIRE 16 -1 (25 3450)(475 3450);
WIRE 16 -1 (25 3400)(475 3400);
WIRE 16 -1 (25 3350)(475 3350);
WIRE 16 -1 (25 3300)(475 3300);
WIRE 16 -1 (2875 3200)(3350 3200);
WIRE 16 -1 (2875 3150)(3350 3150);
WIRE 16 -1 (2875 3100)(3350 3100);
WIRE 16 -1 (2875 3050)(3350 3050);
WIRE 16 -1 (2875 3000)(3350 3000);
WIRE 16 -1 (2875 2950)(3350 2950);
WIRE 16 -1 (2875 2900)(3350 2900);
WIRE 16 -1 (2875 2850)(3350 2850);
WIRE 16 -1 (2875 2800)(3350 2800);
WIRE 16 -1 (2875 2750)(3350 2750);
WIRE 16 -1 (2875 2700)(3350 2700);
WIRE 16 -1 (2875 2650)(3350 2650);
WIRE 16 -1 (2875 2600)(3350 2600);
WIRE 16 -1 (2875 2550)(3350 2550);
WIRE 16 -1 (2875 2500)(3350 2500);
WIRE 16 -1 (2875 2450)(3350 2450);
WIRE 16 -1 (2875 4050)(3350 4050);
WIRE 16 -1 (2875 4000)(3350 4000);
WIRE 16 -1 (2875 3950)(3350 3950);
WIRE 16 -1 (2875 3900)(3350 3900);
WIRE 16 -1 (2875 3850)(3350 3850);
WIRE 16 -1 (2875 3800)(3350 3800);
WIRE 16 -1 (2875 3750)(3350 3750);
WIRE 16 -1 (2875 3700)(3350 3700);
WIRE 16 -1 (2875 3650)(3350 3650);
WIRE 16 -1 (2875 3600)(3350 3600);
WIRE 16 -1 (2875 3550)(3350 3550);
WIRE 16 -1 (2875 3500)(3350 3500);
WIRE 16 -1 (2875 3450)(3350 3450);
WIRE 16 -1 (2875 3400)(3350 3400);
WIRE 16 -1 (2875 3350)(3350 3350);
WIRE 16 -1 (2875 3300)(3350 3300);
WIRE 16 -1 (25 425)(475 425);
WIRE 16 -1 (25 375)(475 375);
WIRE 16 -1 (25 325)(475 325);
WIRE 16 -1 (25 275)(475 275);
WIRE 16 -1 (25 225)(475 225);
WIRE 16 -1 (25 175)(475 175);
WIRE 16 -1 (25 125)(475 125);
WIRE 16 -1 (25 75)(475 75);
WIRE 16 -1 (25 25)(475 25);
WIRE 16 -1 (25 -25)(475 -25);
WIRE 16 -1 (25 -75)(475 -75);
WIRE 16 -1 (25 -125)(475 -125);
WIRE 16 -1 (25 -175)(475 -175);
WIRE 16 -1 (25 -225)(475 -225);
WIRE 16 -1 (25 -275)(475 -275);
WIRE 16 -1 (25 -325)(475 -325);
WIRE 16 -1 (25 1275)(475 1275);
WIRE 16 -1 (25 1225)(475 1225);
WIRE 16 -1 (25 1175)(475 1175);
WIRE 16 -1 (25 1125)(475 1125);
WIRE 16 -1 (25 1075)(475 1075);
WIRE 16 -1 (25 1025)(475 1025);
WIRE 16 -1 (25 975)(475 975);
WIRE 16 -1 (25 925)(475 925);
WIRE 16 -1 (25 875)(475 875);
WIRE 16 -1 (25 825)(475 825);
WIRE 16 -1 (25 775)(475 775);
WIRE 16 -1 (25 725)(475 725);
WIRE 16 -1 (25 675)(475 675);
WIRE 16 -1 (25 625)(475 625);
WIRE 16 -1 (25 575)(475 575);
WIRE 16 -1 (25 525)(475 525);
WIRE 16 -1 (2875 425)(3350 425);
WIRE 16 -1 (2875 375)(3350 375);
WIRE 16 -1 (2875 325)(3350 325);
WIRE 16 -1 (2875 275)(3350 275);
WIRE 16 -1 (2875 225)(3350 225);
WIRE 16 -1 (2875 175)(3350 175);
WIRE 16 -1 (2875 125)(3350 125);
WIRE 16 -1 (2875 75)(3350 75);
WIRE 16 -1 (2875 25)(3350 25);
WIRE 16 -1 (2875 -25)(3350 -25);
WIRE 16 -1 (2875 -75)(3350 -75);
WIRE 16 -1 (2875 -125)(3350 -125);
WIRE 16 -1 (2875 -175)(3350 -175);
WIRE 16 -1 (2875 -225)(3350 -225);
WIRE 16 -1 (2875 -275)(3350 -275);
WIRE 16 -1 (2875 -325)(3350 -325);
WIRE 16 -1 (2875 1275)(3350 1275);
WIRE 16 -1 (2875 1225)(3350 1225);
WIRE 16 -1 (2875 1175)(3350 1175);
WIRE 16 -1 (2875 1125)(3350 1125);
WIRE 16 -1 (2875 1075)(3350 1075);
WIRE 16 -1 (2875 1025)(3350 1025);
WIRE 16 -1 (2875 975)(3350 975);
WIRE 16 -1 (2875 925)(3350 925);
WIRE 16 -1 (2875 875)(3350 875);
WIRE 16 -1 (2875 825)(3350 825);
WIRE 16 -1 (2875 775)(3350 775);
WIRE 16 -1 (2875 725)(3350 725);
WIRE 16 -1 (2875 675)(3350 675);
WIRE 16 -1 (2875 625)(3350 625);
WIRE 16 -1 (2875 575)(3350 575);
WIRE 16 -1 (2875 525)(3350 525);
FORCENOTE
20210818 MODIFY FOR GT
(375 4875) 0;
DISPLAY LEFT (375 4875);
DISPLAY 2.510638 (375 4875);
PAINT PINK (375 4875);
QUIT
